# Lightning_PEB_Pick & place.xlsx — Sheet1 (pick-and-place)
| 15105-1.1116WPH0457.brd |  |  |  |  |  |  |  |  |
| Date  Tue Mar 07 11:50:07 2017 |  |  |  |  |  |  |  |  |
| Total Components:  2560 |  |  |  |  |  |  |  |  |
| Component Report |  |  |  |  |  |  |  |  |
| REFDES | COMP_DEVICE_TYPE | COMP_VALUE | COMP_TOL | COMP_PACKAGE | SYM_X | SYM_Y | SYM_ROTATE | SYM_MIRROR |
| BAT1 | AAA-BAT-043-K01 | AAA-BAT-043-K03-GP | 022.70007.0091 | AAA-BAT-043-K01 | 4732.3100000000004 | 2552.4499999999998 | 270 | NO |
| C1 | C402H22 | SCD22U10V2KX-1GP | 78.22423.5FL | C402H22 | 10785 | 500 | 90 | NO |
| C2 | C402H22 | SCD22U10V2KX-1GP | 78.22423.5FL | C402H22 | 10785 | 535 | 90 | NO |
| C4 | C402H22 | SCD1U16V2KX-3GP | 78.10421.2FL | C402H22 | 8960 | 45 | 180 | NO |
| C6 | C402H22 | SCD22U10V2KX-1GP | 78.22423.5FL | C402H22 | 10785 | 605 | 90 | NO |
| C7 | C402H22 | SCD22U10V2KX-1GP | 78.22423.5FL | C402H22 | 10785 | 570 | 90 | NO |
| C8 | C402H22 | SCD22U10V2KX-1GP | 78.22423.5FL | C402H22 | 11279 | 1333 | 90 | NO |
| C9 | C402H22 | SCD22U10V2KX-1GP | 78.22423.5FL | C402H22 | 11279 | 1298 | 90 | NO |
| C10 | C402H22 | SCD22U10V2KX-1GP | 78.22423.5FL | C402H22 | 11385 | 1320 | 0 | NO |
| C11 | C402H22 | SCD22U10V2KX-1GP | 78.22423.5FL | C402H22 | 11420 | 1320 | 0 | NO |
| C12 | C402H22 | SCD22U10V2KX-1GP | 78.22423.5FL | C402H22 | 11579.07 | 1326.54 | 0 | NO |
| C13 | C402H22 | SCD22U10V2KX-1GP | 78.22423.5FL | C402H22 | 11614.07 | 1326.54 | 0 | NO |
| C14 | C402H22 | SCD22U10V2KX-1GP | 78.22423.5FL | C402H22 | 11821.61 | 1321.27 | 0 | NO |
| C15 | C402H22 | SCD22U10V2KX-1GP | 78.22423.5FL | C402H22 | 11786.61 | 1321.27 | 0 | NO |
| C16 | C402H22 | SCD22U10V2KX-1GP | 78.22423.5FL | C402H22 | 11874.35 | 1320.48 | 0 | NO |
| C17 | C402H22 | SCD22U10V2KX-1GP | 78.22423.5FL | C402H22 | 12044.49 | 1319.3 | 0 | NO |
| C18 | C402H22 | SCD22U10V2KX-1GP | 78.22423.5FL | C402H22 | 12079.49 | 1319.3 | 0 | NO |
| C19 | C402H22 | SCD22U10V2KX-1GP | 78.22423.5FL | C402H22 | 12219.48 | 1321.09 | 0 | NO |
| C20 | C402H22 | SCD22U10V2KX-1GP | 78.22423.5FL | C402H22 | 12254.48 | 1321.09 | 0 | NO |
| C21 | C402H22 | SCD22U10V2KX-1GP | 78.22423.5FL | C402H22 | 12308.09 | 1321.12 | 0 | NO |
| C22 | C402H22 | SCD22U10V2KX-1GP | 78.22423.5FL | C402H22 | 12343.09 | 1321.12 | 0 | NO |
| C23 | C402H22 | SCD22U10V2KX-1GP | 78.22423.5FL | C402H22 | 12395 | 1320 | 0 | NO |
| C24 | C402H22 | SCD22U10V2KX-1GP | 78.22423.5FL | C402H22 | 11909.35 | 1320.48 | 0 | NO |
| C25 | C402H22 | SCD22U10V2KX-1GP | 78.22423.5FL | C402H22 | 11960 | 1320 | 0 | NO |
| C26 | C402H22 | SCD22U10V2KX-1GP | 78.22423.5FL | C402H22 | 11995 | 1320 | 0 | NO |
| C27 | C0201H13 | SCD1U16V1KX-1-GP | 078.10421.09S1 | C0201H13 | 9416 | 2126 | 90 | YES |
| C28 | C0201H13 | SCD1U16V1KX-1-GP | 078.10421.09S1 | C0201H13 | 9337 | 2126 | 270 | YES |
| C29 | C0201H13 | SCD1U16V1KX-1-GP | 078.10421.09S1 | C0201H13 | 9256 | 2126 | 270 | YES |
| C30 | C0201H13 | SCD1U16V1KX-1-GP | 078.10421.09S1 | C0201H13 | 9416 | 2047 | 270 | YES |
| C31 | C0201H13 | SCD1U16V1KX-1-GP | 078.10421.09S1 | C0201H13 | 9337 | 1929 | 90 | YES |
| C32 | C0201H13 | SCD1U16V1KX-1-GP | 078.10421.09S1 | C0201H13 | 9337 | 2047 | 270 | YES |
| C33 | C0201H13 | SCD1U16V1KX-1-GP | 078.10421.09S1 | C0201H13 | 9256 | 2047 | 270 | YES |
| C34 | C0201H13 | SCD1U16V1KX-1-GP | 078.10421.09S1 | C0201H13 | 9492 | 1929 | 90 | YES |
| C35 | C0201H13 | SCD1U16V1KX-1-GP | 078.10421.09S1 | C0201H13 | 9416 | 1929 | 90 | YES |
| C36 | C0201H13 | SCD1U16V1KX-1-GP | 078.10421.09S1 | C0201H13 | 9256 | 1929 | 90 | YES |
| C37 | C0201H13 | SCD1U16V1KX-1-GP | 078.10421.09S1 | C0201H13 | 9727 | 2126.2399999999998 | 90 | YES |
| C38 | C0201H13 | SCD1U16V1KX-1-GP | 078.10421.09S1 | C0201H13 | 9416 | 1851.68 | 90 | YES |
| C39 | C0201H13 | SCD1U16V1KX-1-GP | 078.10421.09S1 | C0201H13 | 9337 | 1851.68 | 90 | YES |
| C40 | C0201H13 | SCD1U16V1KX-1-GP | 078.10421.09S1 | C0201H13 | 9256 | 1851.68 | 270 | YES |
| C41 | C603H36 | SC1U16V3KX-5GP | 78.10521.2BL | C603H36 | 659.65 | 3704.08 | 180 | NO |
| C42 | C402H22 | SCD1U10V2KX-5GP | 78.10423.2FL | C402H22 | 10144.51 | 433.06 | 180 | NO |
| C43 | C402H22 | SCD1U16V2KX-L-GP | 78.10421.L0L | C402H22 | 952.23 | 3907.04 | 0 | NO |
| C44 | C0201H13 | SCD1U16V1KX-1-GP | 078.10421.09S1 | C0201H13 | 9651 | 2126 | 90 | YES |
| C45 | C402H22 | SCD22U10V2KX-1GP | 78.22423.5FL | C402H22 | 12430 | 1320 | 0 | NO |
| C46 | C402H22 | SCD22U10V2KX-1GP | 78.22423.5FL | C402H22 | 12620.44 | 1319.19 | 0 | NO |
| C47 | C402H22 | SCD22U10V2KX-1GP | 78.22423.5FL | C402H22 | 12585.44 | 1319.19 | 0 | NO |
| C48 | C402H22 | SCD22U10V2KX-1GP | 78.22423.5FL | C402H22 | 12738.65 | 1318.22 | 0 | NO |
| C49 | C402H22 | SCD22U10V2KX-1GP | 78.22423.5FL | C402H22 | 12773.65 | 1318.22 | 0 | NO |
| C50 | C402H22 | SCD22U10V2KX-1GP | 78.22423.5FL | C402H22 | 12831.43 | 1317.3 | 0 | NO |
| C51 | C402H22 | SCD22U10V2KX-1GP | 78.22423.5FL | C402H22 | 12866.43 | 1317.3 | 0 | NO |
| C52 | C402H22 | SCD22U10V2KX-1GP | 78.22423.5FL | C402H22 | 12926.17 | 1316.27 | 0 | NO |
| C53 | C402H22 | SCD22U10V2KX-1GP | 78.22423.5FL | C402H22 | 12961.17 | 1316.27 | 0 | NO |
| C54 | C402H22 | SCD22U10V2KX-1GP | 78.22423.5FL | C402H22 | 13464.25 | 8363.01 | 180 | NO |
| C55 | C402H22 | SCD22U10V2KX-1GP | 78.22423.5FL | C402H22 | 13504.25 | 8363.01 | 180 | NO |
| C56 | C402H22 | SCD22U10V2KX-1GP | 78.22423.5FL | C402H22 | 13338.27 | 8363.01 | 180 | NO |
| C57 | C402H22 | SCD22U10V2KX-1GP | 78.22423.5FL | C402H22 | 13378.27 | 8363.01 | 180 | NO |
| C58 | C402H22 | SCD22U10V2KX-1GP | 78.22423.5FL | C402H22 | 13212.29 | 8363.01 | 180 | NO |
| C59 | C402H22 | SCD22U10V2KX-1GP | 78.22423.5FL | C402H22 | 13252.29 | 8363.01 | 180 | NO |
| C60 | C402H22 | SCD22U10V2KX-1GP | 78.22423.5FL | C402H22 | 13086.3 | 8363.01 | 180 | NO |
| C61 | C402H22 | SCD22U10V2KX-1GP | 78.22423.5FL | C402H22 | 13126.3 | 8363.01 | 180 | NO |
| C62 | C402H22 | SCD22U10V2KX-1GP | 78.22423.5FL | C402H22 | 12834.33 | 8363.01 | 180 | NO |
| C63 | C402H22 | SCD22U10V2KX-1GP | 78.22423.5FL | C402H22 | 12874.33 | 8363.01 | 180 | NO |
| C64 | C402H22 | SCD22U10V2KX-1GP | 78.22423.5FL | C402H22 | 12708.35 | 8363.01 | 180 | NO |
| C65 | C402H22 | SCD22U10V2KX-1GP | 78.22423.5FL | C402H22 | 12748.35 | 8363.01 | 180 | NO |
| C66 | C402H22 | SCD22U10V2KX-1GP | 78.22423.5FL | C402H22 | 12622.37 | 8363.01 | 180 | NO |
| C67 | C402H22 | SCD22U10V2KX-1GP | 78.22423.5FL | C402H22 | 12582.37 | 8363.01 | 180 | NO |
| C68 | C402H22 | SCD22U10V2KX-1GP | 78.22423.5FL | C402H22 | 12456.38 | 8363.01 | 180 | NO |
| C69 | C402H22 | SCD22U10V2KX-1GP | 78.22423.5FL | C402H22 | 12496.38 | 8363.01 | 180 | NO |
| C70 | C402H22 | SCD22U10V2KX-1GP | 78.22423.5FL | C402H22 | 12330.4 | 8363.01 | 180 | NO |
| C71 | C402H22 | SCD22U10V2KX-1GP | 78.22423.5FL | C402H22 | 12370.4 | 8363.01 | 180 | NO |
| C72 | C402H22 | SCD22U10V2KX-1GP | 78.22423.5FL | C402H22 | 12204.41 | 8363.01 | 180 | NO |
| C73 | C402H22 | SCD22U10V2KX-1GP | 78.22423.5FL | C402H22 | 12244.41 | 8363.01 | 180 | NO |
| C74 | C402H22 | SCD22U10V2KX-1GP | 78.22423.5FL | C402H22 | 11889.45 | 8363.01 | 180 | NO |
| C75 | C402H22 | SCD22U10V2KX-1GP | 78.22423.5FL | C402H22 | 11929.45 | 8363.01 | 180 | NO |
| C76 | C402H22 | SCD22U10V2KX-1GP | 78.22423.5FL | C402H22 | 11763.47 | 8363.01 | 180 | NO |
| C77 | C402H22 | SCD22U10V2KX-1GP | 78.22423.5FL | C402H22 | 11803.47 | 8363.01 | 180 | NO |
| C78 | C402H22 | SCD22U10V2KX-1GP | 78.22423.5FL | C402H22 | 11582.99 | 8363.01 | 180 | NO |
| C79 | C402H22 | SCD22U10V2KX-1GP | 78.22423.5FL | C402H22 | 11542.99 | 8363.01 | 180 | NO |
| C80 | C402H22 | SCD22U10V2KX-1GP | 78.22423.5FL | C402H22 | 11417.01 | 8363.01 | 180 | NO |
| C91 | C402H22 | SCD22U10V2KX-1GP | 78.22423.5FL | C402H22 | 11457.01 | 8363.01 | 180 | NO |
| C92 | C402H22 | SCD22U10V2KX-1GP | 78.22423.5FL | C402H22 | 11331.03 | 8363.01 | 180 | NO |
| C93 | C402H22 | SCD22U10V2KX-1GP | 78.22423.5FL | C402H22 | 11291.03 | 8363.01 | 180 | NO |
| C94 | C402H22 | SCD22U10V2KX-1GP | 78.22423.5FL | C402H22 | 11165.04 | 8363.01 | 180 | NO |
| C95 | C402H22 | SCD22U10V2KX-1GP | 78.22423.5FL | C402H22 | 11205.04 | 8363.01 | 180 | NO |
| C96 | C402H22 | SCD22U10V2KX-1GP | 78.22423.5FL | C402H22 | 11079.06 | 8363.01 | 180 | NO |
| C97 | C402H22 | SCD22U10V2KX-1GP | 78.22423.5FL | C402H22 | 11039.06 | 8363.01 | 180 | NO |
| C98 | C402H22 | SCD22U10V2KX-1GP | 78.22423.5FL | C402H22 | 10953.07 | 8363.01 | 180 | NO |
| C99 | C402H22 | SCD22U10V2KX-1GP | 78.22423.5FL | C402H22 | 10913.07 | 8363.01 | 180 | NO |
| C100 | C402H22 | SCD22U10V2KX-1GP | 78.22423.5FL | C402H22 | 10827.09 | 8363.01 | 180 | NO |
| C101 | C402H22 | SCD22U10V2KX-1GP | 78.22423.5FL | C402H22 | 10787.09 | 8363.01 | 180 | NO |
| C102 | C402H22 | SCD22U10V2KX-1GP | 78.22423.5FL | C402H22 | 10701.11 | 8363.01 | 180 | NO |
| C103 | C402H22 | SCD22U10V2KX-1GP | 78.22423.5FL | C402H22 | 10661.11 | 8363.01 | 180 | NO |
| C104 | C402H22 | SCD22U10V2KX-1GP | 78.22423.5FL | C402H22 | 10575.12 | 8363.01 | 180 | NO |
| C105 | C402H22 | SCD22U10V2KX-1GP | 78.22423.5FL | C402H22 | 10535.12 | 8363.01 | 180 | NO |
| C106 | C402H22 | SCD22U10V2KX-1GP | 78.22423.5FL | C402H22 | 10449.14 | 8363.01 | 180 | NO |
| C107 | C402H22 | SCD22U10V2KX-1GP | 78.22423.5FL | C402H22 | 10409.14 | 8363.01 | 180 | NO |
| C108 | C402H22 | SCD22U10V2KX-1GP | 78.22423.5FL | C402H22 | 8543.6200000000008 | 8363.01 | 180 | NO |
| C109 | C402H22 | SCD22U10V2KX-1GP | 78.22423.5FL | C402H22 | 8503.6200000000008 | 8363.01 | 180 | NO |
| C110 | C402H22 | SCD22U10V2KX-1GP | 78.22423.5FL | C402H22 | 8417.64 | 8363.01 | 180 | NO |
| C111 | C402H22 | SCD22U10V2KX-1GP | 78.22423.5FL | C402H22 | 8377.64 | 8363.01 | 180 | NO |
| C112 | C402H22 | SCD22U10V2KX-1GP | 78.22423.5FL | C402H22 | 8165.67 | 8363.01 | 180 | NO |
| C113 | C402H22 | SCD22U10V2KX-1GP | 78.22423.5FL | C402H22 | 8125.67 | 8363.01 | 180 | NO |
| C114 | C402H22 | SCD22U10V2KX-1GP | 78.22423.5FL | C402H22 | 8039.69 | 8363.01 | 180 | NO |
| C115 | C402H22 | SCD22U10V2KX-1GP | 78.22423.5FL | C402H22 | 7999.69 | 8363.01 | 180 | NO |
| C116 | C402H22 | SCD22U10V2KX-1GP | 78.22423.5FL | C402H22 | 7913.7 | 8363.01 | 180 | NO |
| C117 | C402H22 | SCD22U10V2KX-1GP | 78.22423.5FL | C402H22 | 7873.7 | 8363.01 | 180 | NO |
| C118 | C402H22 | SCD22U10V2KX-1GP | 78.22423.5FL | C402H22 | 7787.72 | 8363.01 | 180 | NO |
| C119 | C402H22 | SCD22U10V2KX-1GP | 78.22423.5FL | C402H22 | 7747.72 | 8363.01 | 180 | NO |
| C120 | C402H22 | SCD22U10V2KX-1GP | 78.22423.5FL | C402H22 | 7661.74 | 8363.01 | 180 | NO |
| C121 | C402H22 | SCD22U10V2KX-1GP | 78.22423.5FL | C402H22 | 7621.74 | 8363.01 | 180 | NO |
| C122 | C402H22 | SCD22U10V2KX-1GP | 78.22423.5FL | C402H22 | 7535.76 | 8363.01 | 180 | NO |
| C123 | C402H22 | SCD22U10V2KX-1GP | 78.22423.5FL | C402H22 | 7495.76 | 8363.01 | 180 | NO |
| C124 | C402H22 | SCD22U10V2KX-1GP | 78.22423.5FL | C402H22 | 7409.77 | 8363.01 | 180 | NO |
| C125 | C402H22 | SCD22U10V2KX-1GP | 78.22423.5FL | C402H22 | 7369.77 | 8363.01 | 180 | NO |
| C126 | C402H22 | SCD22U10V2KX-1GP | 78.22423.5FL | C402H22 | 7283.79 | 8363.01 | 180 | NO |
| C127 | C402H22 | SCD22U10V2KX-1GP | 78.22423.5FL | C402H22 | 7243.79 | 8363.01 | 180 | NO |
| C128 | C402H22 | SCD22U10V2KX-1GP | 78.22423.5FL | C402H22 | 6928.82 | 8363.01 | 180 | NO |
| C129 | C402H22 | SCD1U10V2KX-5GP | 78.10423.2FL | C402H22 | 4896.8 | 1318.05 | 180 | YES |
| C130 | C402H22 | SCD1U10V2KX-5GP | 78.10423.2FL | C402H22 | 4932.45 | 1318.25 | 180 | YES |
| C131 | C402H22 | SCD1U10V2KX-5GP | 78.10423.2FL | C402H22 | 11751.56 | 1363.19 | 180 | YES |
| C132 | C402H22 | SCD047U25V2KX-GP | 78.47322.2FL | C402H22 | 4590.71 | 1205.4100000000001 | 180 | NO |
| C133 | C402H22 | SCD1U10V2KX-5GP | 78.10423.2FL | C402H22 | 4576.92 | 1142.54 | 270 | NO |
| C134 | C402H22 | SCD1U10V2KX-5GP | 78.10423.2FL | C402H22 | 12043.35 | 1366.91 | 0 | YES |
| C135 | C402H22 | SCD047U25V2KX-GP | 78.47322.2FL | C402H22 | 8046 | 1063 | 270 | NO |
| C136 | C402H22 | SCD1U10V2KX-5GP | 78.10423.2FL | C402H22 | 8046 | 1028 | 270 | NO |
| C137 | C402H22 | SCD22U10V2KX-1GP | 78.22423.5FL | C402H22 | 6968.82 | 8363.01 | 180 | NO |
| C138 | C402H22 | SCD22U10V2KX-1GP | 78.22423.5FL | C402H22 | 6802.84 | 8363.01 | 180 | NO |
| C139 | C402H22 | SCD22U10V2KX-1GP | 78.22423.5FL | C402H22 | 6842.84 | 8363.01 | 180 | NO |
| C140 | C402H22 | SCD22U10V2KX-1GP | 78.22423.5FL | C402H22 | 6676.85 | 8363.01 | 180 | NO |
| C141 | C402H22 | SCD22U10V2KX-1GP | 78.22423.5FL | C402H22 | 6716.85 | 8363.01 | 180 | NO |
| C142 | C402H22 | SCD047U25V2KX-GP | 78.47322.2FL | C402H22 | 7592 | 1128 | 270 | NO |
| C143 | C402H22 | SCD1U10V2KX-5GP | 78.10423.2FL | C402H22 | 7592 | 1093 | 270 | NO |
| C144 | C402H22 | SCD22U10V2KX-1GP | 78.22423.5FL | C402H22 | 4275.91 | 8363.01 | 180 | NO |
| C147 | C402H22 | SCD22U10V2KX-1GP | 78.22423.5FL | C402H22 | 4235.91 | 8363.01 | 180 | NO |
| C148 | C402H22 | SCD22U10V2KX-1GP | 78.22423.5FL | C402H22 | 4149.93 | 8363.01 | 180 | NO |
| C149 | C402H22 | SCD22U10V2KX-1GP | 78.22423.5FL | C402H22 | 4109.93 | 8363.01 | 180 | NO |
| C150 | C402H22 | SCD22U10V2KX-1GP | 78.22423.5FL | C402H22 | 4023.94 | 8363.01 | 180 | NO |
| C151 | C402H22 | SCD1U16V2KX-3GP | 78.10421.2FL | C402H22 | 10072.120000000001 | 359.19 | 270 | YES |
| C152 | C402H22 | SCD1U16V2JX-1-GP | 78.10431.2FL | C402H22 | 2539.88 | 5776.65 | 270 | NO |
| C153 | C402H22 | SC100P50V2JN-3GP | 78.10134.1FL | C402H22 | 10380.17 | 147.1 | 90 | YES |
| C154 | C402H22 | SCD22U10V2KX-1GP | 78.22423.5FL | C402H22 | 3983.94 | 8363.01 | 180 | NO |
| C155 | C402H22 | SCD1U16V2JX-1-GP | 78.10431.2FL | C402H22 | 617.99 | 3743.57 | 180 | NO |
| C156 | C402H22 | SCD22U10V2KX-1GP | 78.22423.5FL | C402H22 | 3857.96 | 8363.01 | 180 | NO |
| C157 | C402H22 | SCD22U10V2KX-1GP | 78.22423.5FL | C402H22 | 3897.96 | 8363.01 | 180 | NO |
| C160 | C402H22 | SCD22U10V2KX-1GP | 78.22423.5FL | C402H22 | 6550.87 | 8363.01 | 180 | NO |
| C161 | C402H22 | SCD22U10V2KX-1GP | 78.22423.5FL | C402H22 | 6590.87 | 8363.01 | 180 | NO |
| C164 | C402H22 | SCD22U10V2KX-1GP | 78.22423.5FL | C402H22 | 6330.4 | 8363.01 | 180 | NO |
| C165 | C402H22 | SCD22U10V2KX-1GP | 78.22423.5FL | C402H22 | 6370.4 | 8363.01 | 180 | NO |
| C168 | C402H22 | SCD22U10V2KX-1GP | 78.22423.5FL | C402H22 | 6204.42 | 8363.01 | 180 | NO |
| C169 | C402H22 | SCD22U10V2KX-1GP | 78.22423.5FL | C402H22 | 6244.42 | 8363.01 | 180 | NO |
| C170 | C805H58 | SC10U6D3V5KX-4GP | 78.10620.21L | C805H58 | 1240.51 | 6509.36 | 180 | NO |
| C171 | C402H22 | SCD1U16V2KX-3GP | 78.10421.2FL | C402H22 | 1498.51 | 6259.36 | 180 | YES |
| C172 | C402H22 | SCD1U16V2KX-3GP | 78.10421.2FL | C402H22 | 1300.51 | 6501.46 | 180 | NO |
| C173 | C402H22 | SCD1U16V2KX-3GP | 78.10421.2FL | C402H22 | 1558.51 | 6259.36 | 180 | YES |
| C175 | C402H22 | SCD1U16V2KX-3GP | 78.10421.2FL | C402H22 | 1458.09 | 5766.3 | 0 | NO |
| C176 | C402H22 | SCD1U16V2KX-3GP | 78.10421.2FL | C402H22 | 1183.51 | 5764.36 | 0 | NO |
| C177 | C402H22 | SCD01U25V2KX-3GP | 78.10322.2FL | C402H22 | 1355.51 | 6439.36 | 90 | NO |
| C178 | C402H22 | SCD1U16V2KX-3GP | 78.10421.2FL | C402H22 | 1523.19 | 5767.2 | 0 | NO |
| C179 | C402H22 | SCD01U25V2KX-3GP | 78.10322.2FL | C402H22 | 1450.51 | 6439.36 | 90 | NO |
| C180 | C402H22 | SC1U10V2KX-4-GP | 78.10523.8FL | C402H22 | 1450.51 | 6484.36 | 90 | NO |
| C181 | C402H22 | SCD1U16V2KX-3GP | 78.10421.2FL | C402H22 | 1608.51 | 6259.36 | 180 | YES |
| C182 | C402H22 | SCD1U16V2KX-3GP | 78.10421.2FL | C402H22 | 1658.51 | 6259.36 | 180 | YES |
| C183 | C402H22 | SCD1U16V2KX-3GP | 78.10421.2FL | C402H22 | 1138.51 | 5764.36 | 0 | NO |
| C184 | C402H22 | SCD1U16V2KX-3GP | 78.10421.2FL | C402H22 | 1332.99 | 5767.2 | 180 | NO |
| C185 | C402H22 | SCD1U16V2KX-3GP | 78.10421.2FL | C402H22 | 1597.51 | 5766.36 | 0 | NO |
| C186 | C402H22 | SCD1U16V2KX-3GP | 78.10421.2FL | C402H22 | 2673 | 2950 | 180 | NO |
| C187 | C402H22 | SCD1U16V2KX-3GP | 78.10421.2FL | C402H22 | 810 | 5840 | 0 | NO |
| C188 | C603H36 | SC1U10V3KX-4GP-U | 78.10523.2BL | C603H36 | 2130 | 4735 | 90 | NO |
| C189 | C402H22 | SCD1U16V2KX-3GP | 78.10421.2FL | C402H22 | 2135 | 5120 | 0 | NO |
| C190 | C402H22 | SCD1U16V2KX-3GP | 78.10421.2FL | C402H22 | 2115 | 5175 | 270 | NO |
| C191 | C402H22 | SCD1U16V2KX-3GP | 78.10421.2FL | C402H22 | 2095 | 5120 | 0 | NO |
| C192 | C402H22 | SC1U10V2KX-4-GP | 78.10523.8FL | C402H22 | 2225 | 5120 | 180 | NO |
| C193 | C402H22 | SC100P50V2JN-3GP | 78.10134.1FL | C402H22 | 2260 | 5120 | 180 | NO |
| C194 | C402H22 | SC1U10V2KX-4-GP | 78.10523.8FL | C402H22 | 740 | 5740 | 180 | NO |
| C195 | C402H22 | SCD1U16V2KX-3GP | 78.10421.2FL | C402H22 | 840 | 5725 | 180 | NO |
| C196 | C402H22 | SC100P50V2JN-3GP | 78.10134.1FL | C402H22 | 805 | 5725 | 180 | NO |
| C197 | C402H22 | SC1U10V2KX-4-GP | 78.10523.8FL | C402H22 | 1375.51 | 6239.36 | 180 | YES |
| C198 | C402H22 | SC1U10V2KX-4-GP | 78.10523.8FL | C402H22 | 1268.51 | 6284.36 | 180 | YES |
| C199 | C402H22 | SC1U10V2KX-4-GP | 78.10523.8FL | C402H22 | 1203.51 | 6284.36 | 180 | YES |
| C200 | C402H22 | SC1U10V2KX-4-GP | 78.10523.8FL | C402H22 | 1796.21 | 5984.36 | 90 | NO |
| C201 | C402H22 | SC1U10V2KX-4-GP | 78.10523.8FL | C402H22 | 740 | 5630 | 0 | NO |
| C202 | C402H22 | SCD1U16V2KX-3GP | 78.10421.2FL | C402H22 | 805 | 5645 | 0 | NO |
| C203 | C402H22 | SC100P50V2JN-3GP | 78.10134.1FL | C402H22 | 840 | 5645 | 0 | NO |
| C204 | C402H22 | SC1U10V2KX-4-GP | 78.10523.8FL | C402H22 | 1485 | 5235 | 0 | YES |
| C205 | C402H22 | SC1U10V2KX-4-GP | 78.10523.8FL | C402H22 | 1640.19 | 5217.2 | 270 | YES |
| C206 | C402H22 | SC1U10V2KX-4-GP | 78.10523.8FL | C402H22 | 1640 | 5125 | 270 | YES |
| C207 | C402H22 | SC1U10V2KX-4-GP | 78.10523.8FL | C402H22 | 1405 | 5220 | 90 | YES |
| C208 | C402H22 | SC1U10V2KX-4-GP | 78.10523.8FL | C402H22 | 1640 | 5090 | 270 | YES |
| C209 | C402H22 | SC220P50V2KX-3GP | 78.22124.2FL | C402H22 | 1387.72 | 5054.67 | 90 | YES |
| C210 | C402H22 | SC1U10V2KX-4-GP | 78.10523.8FL | C402H22 | 1400.16 | 5171.2 | 90 | YES |
| C211 | C402H22 | SC220P50V2KX-3GP | 78.22124.2FL | C402H22 | 1585 | 5245 | 0 | YES |
| C212 | C402H22 | SC1U10V2KX-4-GP | 78.10523.8FL | C402H22 | 1432.17 | 4999.6000000000004 | 180 | YES |
| C213 | C402H22 | SC1U10V2KX-4-GP | 78.10523.8FL | C402H22 | 1390 | 5105 | 90 | YES |
| C214 | C402H22 | SC1U10V2KX-4-GP | 78.10523.8FL | C402H22 | 1640 | 5160 | 270 | YES |
| C215 | C402H22 | SC1U10V2KX-4-GP | 78.10523.8FL | C402H22 | 1640 | 5055 | 270 | YES |
| C216 | C402H22 | SC1U10V2KX-4-GP | 78.10523.8FL | C402H22 | 1568.62 | 5000.1099999999997 | 180 | YES |
| C217 | C402H22 | SC1U10V2KX-4-GP | 78.10523.8FL | C402H22 | 1529.16 | 4997.3599999999997 | 180 | YES |
| C218 | C402H22 | SC1U10V2KX-4-GP | 78.10523.8FL | C402H22 | 1469.6 | 4998.3 | 180 | YES |
| C219 | C402H22 | SC1U10V2KX-4-GP | 78.10523.8FL | C402H22 | 1835 | 4433 | 270 | YES |
| C220 | C402H22 | SCD1U10V2KX-5GP | 78.10423.2FL | C402H22 | 5038.2700000000004 | 1319.04 | 180 | YES |
| C221 | C402H22 | SCD1U10V2KX-5GP | 78.10423.2FL | C402H22 | 5003.32 | 1319.64 | 180 | YES |
| C222 | C402H22 | SCD1U10V2KX-5GP | 78.10423.2FL | C402H22 | 6039.24 | 1320.53 | 180 | YES |
| C223 | C402H22 | SCD1U10V2KX-5GP | 78.10423.2FL | C402H22 | 5595.91 | 1355.95 | 180 | YES |
| C224 | C402H22 | SCD1U10V2KX-5GP | 78.10423.2FL | C402H22 | 5535 | 1340.94 | 90 | YES |
| C225 | C402H22 | SCD1U10V2KX-5GP | 78.10423.2FL | C402H22 | 5630.02 | 1355.95 | 180 | YES |
| C226 | C402H22 | SCD1U10V2KX-5GP | 78.10423.2FL | C402H22 | 6005.22 | 1320.53 | 180 | YES |
| C227 | C402H22 | SCD1U10V2KX-5GP | 78.10423.2FL | C402H22 | 5534.8 | 1375.38 | 90 | YES |
| C228 | C402H22 | SCD1U10V2KX-5GP | 78.10423.2FL | C402H22 | 5936.36 | 1320.68 | 180 | YES |
| C229 | C402H22 | SCD1U10V2KX-5GP | 78.10423.2FL | C402H22 | 5970.44 | 1320.68 | 180 | YES |
| C230 | C402H22 | SCD1U10V2KX-5GP | 78.10423.2FL | C402H22 | 12077.45 | 1366.9 | 0 | YES |
| C231 | C402H22 | SCD1U10V2KX-5GP | 78.10423.2FL | C402H22 | 12407.09 | 1485.53 | 180 | YES |
| C232 | C402H22 | SC1U10V2KX-4-GP | 78.10523.8FL | C402H22 | 451 | 3944 | 90 | NO |
| C233 | C402H22 | SC1U10V2KX-4-GP | 78.10523.8FL | C402H22 | 298 | 3212 | 90 | NO |
| C234 | C402H24 | SC12P50V2JN-3GP | 78.12034.1FL | C402H24 | 385 | 2750 | 180 | NO |
| C235 | C402H24 | SC12P50V2JN-3GP | 78.12034.1FL | C402H24 | 385 | 2826 | 0 | NO |
| C236 | C402H22 | SC1U10V2KX-4-GP | 78.10523.8FL | C402H22 | 2052 | 1981 | 0 | NO |
| C237 | C402H22 | SCD1U10V2KX-5GP | 78.10423.2FL | C402H22 | 12698.34 | 1456.34 | 180 | YES |
| C238 | C402H22 | SCD1U16V2JX-1-GP | 78.10431.2FL | C402H22 | 1235 | 1730 | 270 | NO |
| C239 | C402H22 | SCD1U16V2KX-3GP | 78.10421.2FL | C402H22 | 1450.69 | 6404.2 | 90 | NO |
| C240 | C402H22 | SCD1U16V2JX-1-GP | 78.10431.2FL | C402H22 | 1235 | 1890 | 270 | NO |
| C241 | C402H22 | SC1U10V2KX-4-GP | 78.10523.8FL | C402H22 | 10564 | 444 | 270 | NO |
| C242 | C402H22 | SCD1U10V2KX-5GP | 78.10423.2FL | C402H22 | 12664.32 | 1456.34 | 180 | YES |
| C243 | C402H22 | SCD1U16V2KX-3GP | 78.10421.2FL | C402H22 | 1259 | 7108 | 90 | NO |
| C244 | C402H22 | SCD01U50V2KX-1GP | 78.10324.2FL | C402H22 | 1259 | 7143 | 90 | NO |
| C245 | C603H36 | SC220P50V3JN-GP | 78.22134.1BL | C603H36 | 4837 | 3888 | 90 | NO |
| C246 | C603H36 | SC220P50V3JN-GP | 78.22134.1BL | C603H36 | 4837 | 3678 | 90 | NO |
| C247 | C603H36 | SC220P50V3JN-GP | 78.22134.1BL | C603H36 | 4732 | 3678 | 270 | NO |
| C248 | C603H36 | SC220P50V3JN-GP | 78.22134.1BL | C603H36 | 4732 | 3888 | 270 | NO |
| C249 | C402H22 | SCD1U16V2KX-3GP | 78.10421.2FL | C402H22 | 9005.2199999999993 | 149.66 | 180 | NO |
| C250 | C402H22 | SCD22U10V2KX-1GP | 78.22423.5FL | C402H22 | 6078.43 | 8363.01 | 180 | NO |
| C251 | C402H22 | SCD22U10V2KX-1GP | 78.22423.5FL | C402H22 | 6118.43 | 8363.01 | 180 | NO |
| C252 | C402H22 | SCD22U10V2KX-1GP | 78.22423.5FL | C402H22 | 5952.45 | 8363.01 | 180 | NO |
| C253 | C402H22 | SCD1U16V2KX-3GP | 78.10421.2FL | C402H22 | 1825 | 7105 | 0 | NO |
| C254 | C402H22 | SCD1U10V2KX-5GP | 78.10423.2FL | C402H22 | 12664.32 | 1531.37 | 0 | YES |
| C255 | C402H22 | SCD1U10V2KX-5GP | 78.10423.2FL | C402H22 | 12698.34 | 1531.37 | 0 | YES |
| C256 | C402H22 | SCD1U10V2KX-5GP | 78.10423.2FL | C402H22 | 11716.22 | 1380.28 | 180 | YES |
| C257 | C402H22 | SCD1U10V2KX-5GP | 78.10423.2FL | C402H22 | 11682.07 | 1380.26 | 180 | YES |
| C258 | C603H36 | SC220P50V3JN-GP | 78.22134.1BL | C603H36 | 1324 | 7353 | 180 | NO |
| C259 | C603H36 | SC220P50V3JN-GP | 78.22134.1BL | C603H36 | 1114 | 7353 | 180 | NO |
| C260 | C402H22 | SCD22U10V2KX-1GP | 78.22423.5FL | C402H22 | 5992.45 | 8363.01 | 180 | NO |
| C261 | C603H36 | SC220P50V3JN-GP | 78.22134.1BL | C603H36 | 1114 | 7248 | 0 | NO |
| C262 | C603H36 | SC220P50V3JN-GP | 78.22134.1BL | C603H36 | 1324 | 7248 | 0 | NO |
| C263 | C402H22 | SCD1U16V2KX-3GP | 78.10421.2FL | C402H22 | 2977.29 | 3566.4 | 180 | NO |
| C264 | C402H22 | SC1U10V2KX-4-GP | 78.10523.8FL | C402H22 | 866 | 5903 | 270 | NO |
| C265 | C402H22 | SCD01U50V2KX-1GP | 78.10324.2FL | C402H22 | 1860 | 7105 | 0 | NO |
| C266 | C402H22 | SCD1U16V2JX-1-GP | 78.10431.2FL | C402H22 | 10396.75 | 170.87 | 180 | NO |
| C267 | C402H22 | SC100P50V2JN-3GP | 78.10134.1FL | C402H22 | 2795 | 1220 | 90 | NO |
| C268 | C402H22 | SC100P50V2JN-3GP | 78.10134.1FL | C402H22 | 6215.63 | 2136.08 | 90 | NO |
| C269 | C402H22 | SCD1U16V2KX-3GP | 78.10421.2FL | C402H22 | 7406 | 203 | 270 | NO |
| C270 | C402H22 | SC100P50V2JN-3GP | 78.10134.1FL | C402H22 | 13190 | 2900 | 270 | NO |
| C271 | C402H22 | SC1U10V2KX-4-GP | 78.10523.8FL | C402H22 | 8788 | 546 | 0 | NO |
| C272 | C402H22 | SCD1U16V2KX-3GP | 78.10421.2FL | C402H22 | 1105.51 | 6384.36 | 90 | NO |
| C273 | C402H22 | SCD22U10V2KX-1GP | 78.22423.5FL | C402H22 | 5826.46 | 8363.01 | 180 | NO |
| C274 | C402H22 | SCD1U16V2KX-3GP | 78.10421.2FL | C402H22 | 3314.58 | 2922.48 | 270 | NO |
| C275 | C402H22 | SCD1U16V2KX-3GP | 78.10421.2FL | C402H22 | 815 | 6360 | 0 | NO |
| C276 | C402H22 | SCD1U16V2KX-3GP | 78.10421.2FL | C402H22 | 1084 | 3902 | 0 | NO |
| C277 | C402H22 | SCD1U10V2KX-5GP | 78.10423.2FL | C402H22 | 11785.58 | 1363.18 | 180 | YES |
| C278 | C402H22 | SCD1U10V2KX-5GP | 78.10423.2FL | C402H22 | 12373.08 | 1485.53 | 180 | YES |
| C279 | C402H22 | SCD1U16V2KX-3GP | 78.10421.2FL | C402H22 | 2823 | 5012 | 0 | NO |
| C280 | C402H22 | SCD1U16V2KX-3GP | 78.10421.2FL | C402H22 | 2598.5700000000002 | 5119.4799999999996 | 180 | NO |
| C281 | C402H22 | SCD1U16V2KX-3GP | 78.10421.2FL | C402H22 | 3015 | 4853 | 180 | NO |
| C282 | C402H22 | SCD1U16V2KX-3GP | 78.10421.2FL | C402H22 | 2893 | 4650 | 270 | NO |
| C283 | C402H22 | SCD01U16V2KX-3GP | 78.10321.2FL | C402H22 | 3270.92 | 2959 | 90 | NO |
| C284 | C402H22 | SCD01U16V2KX-3GP | 78.10321.2FL | C402H22 | 2443 | 2320 | 180 | NO |
| C285 | C603H40 | SC2D2U16V3KX-GP-U | 78.22521.5BL | C603H40 | 1157.32 | 2688.2 | 90 | NO |
| C286 | C402H22 | SCD01U16V2KX-3GP | 78.10321.2FL | C402H22 | 1058.6199999999999 | 4304.2 | 270 | NO |
| C287 | C402H22 | SCD01U16V2KX-3GP | 78.10321.2FL | C402H22 | 1058.58 | 4270.04 | 270 | NO |
| C304 | C402H22 | SC1U10V2KX-4-GP | 78.10523.8FL | C402H22 | 2632.29 | 3386.4 | 270 | NO |
| C306 | C402H22 | SC3D9P50V2CN-1GP | 78.3R974.1FL | C402H22 | 5254.09 | 3225.41 | 0 | NO |
| C307 | C402H22 | SC15P50V2JN-2-GP | 78.15034.1FL | C402H22 | 5254.09 | 3305.41 | 180 | NO |
| C313 | C402H22 | SCD22U10V2KX-1GP | 78.22423.5FL | C402H22 | 5866.46 | 8363.01 | 180 | NO |
| C314 | C402H22 | SCD22U10V2KX-1GP | 78.22423.5FL | C402H22 | 5740.48 | 8363.01 | 180 | NO |
| C315 | C402H22 | SCD22U10V2KX-1GP | 78.22423.5FL | C402H22 | 5700.48 | 8363.01 | 180 | NO |
| C319 | C402H22 | SCD1U16V2KX-3GP | 78.10421.2FL | C402H22 | 9437.81 | 253.74 | 90 | NO |
| C322 | C402H22 | SCD1U16V2KX-3GP | 78.10421.2FL | C402H22 | 9290 | 272.7 | 270 | NO |
| C326 | C402H22 | SCD1U16V2KX-3GP | 78.10421.2FL | C402H22 | 2015 | 5805 | 270 | NO |
| C328 | C402H22 | SCD1U16V2KX-3GP | 78.10421.2FL | C402H22 | 9055 | 3330 | 180 | NO |
| C329 | C402H22 | SCD1U16V2KX-3GP | 78.10421.2FL | C402H22 | 219 | 1941 | 180 | NO |
| C330 | C402H22 | SCD1U16V2KX-3GP | 78.10421.2FL | C402H22 | 220 | 1730 | 0 | NO |
| C332 | C402H22 | SCD1U16V2JX-1-GP | 78.10431.2FL | C402H22 | 1359 | 2643 | 270 | NO |
| C333 | C402H22 | SCD1U16V2KX-3GP | 78.10421.2FL | C402H22 | 218 | 1826 | 180 | NO |
| C334 | C402H22 | SCD1U16V2KX-3GP | 78.10421.2FL | C402H22 | 1009 | 1796 | 0 | NO |
| C335 | C402H22 | SCD1U16V2KX-3GP | 78.10421.2FL | C402H22 | 1009 | 1924 | 180 | NO |
| C336 | C402H22 | SC1U10V2KX-4-GP | 78.10523.8FL | C402H22 | 1235 | 1770 | 270 | NO |
| C337 | C402H22 | SC1U10V2KX-4-GP | 78.10523.8FL | C402H22 | 1235 | 1810 | 270 | NO |
| C338 | C402H22 | SC1U10V2KX-4-GP | 78.10523.8FL | C402H22 | 1235 | 1850 | 270 | NO |
| C339 | C1206H75 | SC22UF16V6KX-GP | 78.22621.82L | C1206H75 | 697 | 7007 | 0 | NO |
| C341 | C402H22 | SCD22U10V2KX-1GP | 78.22423.5FL | C402H22 | 5614.49 | 8363.01 | 180 | NO |
| C342 | C402H22 | SCD22U10V2KX-1GP | 78.22423.5FL | C402H22 | 5574.49 | 8363.01 | 180 | NO |
| C343 | C402H22 | SCD22U10V2KX-1GP | 78.22423.5FL | C402H22 | 5488.51 | 8363.01 | 180 | NO |
| C344 | C402H22 | SCD22U10V2KX-1GP | 78.22423.5FL | C402H22 | 5448.51 | 8363.01 | 180 | NO |
| C345 | C402H22 | SCD22U10V2KX-1GP | 78.22423.5FL | C402H22 | 3551.5 | 8363.01 | 180 | NO |
| C346 | C402H22 | SCD22U10V2KX-1GP | 78.22423.5FL | C402H22 | 3511.5 | 8363.01 | 180 | NO |
| C347 | C402H22 | SCD22U10V2KX-1GP | 78.22423.5FL | C402H22 | 3385.51 | 8363.01 | 180 | NO |
| C348 | C402H22 | SCD22U10V2KX-1GP | 78.22423.5FL | C402H22 | 3425.51 | 8363.01 | 180 | NO |
| C349 | C402H22 | SCD22U10V2KX-1GP | 78.22423.5FL | C402H22 | 3259.53 | 8363.01 | 180 | NO |
| C350 | C402H22 | SCD22U10V2KX-1GP | 78.22423.5FL | C402H22 | 3299.53 | 8363.01 | 180 | NO |
| C351 | C402H22 | SCD22U10V2KX-1GP | 78.22423.5FL | C402H22 | 3173.54 | 8363.01 | 180 | NO |
| C352 | C402H22 | SCD22U10V2KX-1GP | 78.22423.5FL | C402H22 | 3133.54 | 8363.01 | 180 | NO |
| C353 | C402H22 | SCD22U10V2KX-1GP | 78.22423.5FL | C402H22 | 2755.59 | 8363.01 | 180 | NO |
| C354 | C402H22 | SCD22U10V2KX-1GP | 78.22423.5FL | C402H22 | 2795.59 | 8363.01 | 180 | NO |
| C355 | C402H22 | SCD22U10V2KX-1GP | 78.22423.5FL | C402H22 | 2629.61 | 8363.01 | 180 | NO |
| C356 | C402H22 | SCD22U10V2KX-1GP | 78.22423.5FL | C402H22 | 2669.61 | 8363.01 | 180 | NO |
| C357 | C402H22 | SCD22U10V2KX-1GP | 78.22423.5FL | C402H22 | 2503.62 | 8363.01 | 180 | NO |
| C358 | C402H22 | SCD22U10V2KX-1GP | 78.22423.5FL | C402H22 | 2543.62 | 8363.01 | 180 | NO |
| C359 | C402H22 | SCD22U10V2KX-1GP | 78.22423.5FL | C402H22 | 2283.15 | 8363.01 | 180 | NO |
| C360 | C402H22 | SCD22U10V2KX-1GP | 78.22423.5FL | C402H22 | 2323.15 | 8363.01 | 180 | NO |
| C361 | C402H22 | SCD22U10V2KX-1GP | 78.22423.5FL | C402H22 | 2157.17 | 8363.01 | 180 | NO |
| C362 | C402H22 | SCD22U10V2KX-1GP | 78.22423.5FL | C402H22 | 2197.17 | 8363.01 | 180 | NO |
| C363 | C402H22 | SCD22U10V2KX-1GP | 78.22423.5FL | C402H22 | 2031.18 | 8363.01 | 180 | NO |
| C364 | C402H22 | SCD22U10V2KX-1GP | 78.22423.5FL | C402H22 | 2071.1799999999998 | 8363.01 | 180 | NO |
| C365 | C402H22 | SCD22U10V2KX-1GP | 78.22423.5FL | C402H22 | 1945.2 | 8363.01 | 180 | NO |
| C366 | C402H22 | SCD22U10V2KX-1GP | 78.22423.5FL | C402H22 | 1905.2 | 8363.01 | 180 | NO |
| C367 | C402H22 | SCD22U10V2KX-1GP | 78.22423.5FL | C402H22 | 894.85 | 4895.04 | 90 | NO |
| C368 | C402H22 | SCD22U10V2KX-1GP | 78.22423.5FL | C402H22 | 894.85 | 4860.04 | 90 | NO |
| C370 | C402H22 | SCD1U25V2KX-2-GP | 78.10422.2FL | C402H22 | 2669.06 | 7703.98 | 180 | NO |
| C371 | C402H22 | SCD1U16V2KX-3GP | 78.10421.2FL | C402H22 | 1434.37 | 4070.34 | 270 | NO |
| C372 | C402H22 | SCD015U25V2KX-GP | 78.15322.2FL | C402H22 | 729 | 7313 | 0 | YES |
| C373 | C402H22 | SCD1U25V2KX-2-GP | 78.10422.2FL | C402H22 | 8733 | 527 | 90 | YES |
| C374 | C402H22 | SCD1U25V2KX-2-GP | 78.10422.2FL | C402H22 | 8894 | 515 | 90 | NO |
| C375 | C402H22 | SCD1U25V2KX-2-GP | 78.10422.2FL | C402H22 | 10434.18 | 339.66 | 0 | NO |
| C377 | C402H22 | SCD039U16V2KX-GP | 78.39321.2FL | C402H22 | 439 | 3017 | 180 | NO |
| C378 | C402H22 | SCD22U10V2KX-1GP | 78.22423.5FL | C402H22 | 3637.48 | 8363.01 | 180 | NO |
| C379 | C402H22 | SCD22U10V2KX-1GP | 78.22423.5FL | C402H22 | 3677.48 | 8363.01 | 180 | NO |
| C380 | C402H22 | SCD22U10V2KX-1GP | 78.22423.5FL | C402H22 | 5364.5 | 1320.6 | 0 | NO |
| C381 | C402H22 | SCD22U10V2KX-1GP | 78.22423.5FL | C402H22 | 5329.5 | 1320.6 | 0 | NO |
| C382 | C402H22 | SCD22U10V2KX-1GP | 78.22423.5FL | C402H22 | 5194.5 | 1320.6 | 0 | NO |
| C383 | C402H22 | SCD22U10V2KX-1GP | 78.22423.5FL | C402H22 | 5159.5 | 1320.6 | 0 | NO |
| C384 | C402H22 | SCD22U10V2KX-1GP | 78.22423.5FL | C402H22 | 5279.5 | 1320.6 | 0 | NO |
| C385 | C402H22 | SCD22U10V2KX-1GP | 78.22423.5FL | C402H22 | 5244.5 | 1320.6 | 0 | NO |
| C386 | C402H22 | SCD22U10V2KX-1GP | 78.22423.5FL | C402H22 | 5449.5 | 1320.6 | 0 | NO |
| C387 | C402H22 | SCD22U10V2KX-1GP | 78.22423.5FL | C402H22 | 5414.5 | 1320.6 | 0 | NO |
| C388 | C402H22 | SCD22U10V2KX-1GP | 78.22423.5FL | C402H22 | 5965 | 1320 | 0 | NO |
| C389 | C402H22 | SCD22U10V2KX-1GP | 78.22423.5FL | C402H22 | 5930 | 1320 | 0 | NO |
| C390 | C402H22 | SCD22U10V2KX-1GP | 78.22423.5FL | C402H22 | 5743 | 1319.8 | 0 | NO |
| C391 | C402H22 | SCD22U10V2KX-1GP | 78.22423.5FL | C402H22 | 5777.3 | 1319.8 | 0 | NO |
| C392 | C402H22 | SCD22U10V2KX-1GP | 78.22423.5FL | C402H22 | 5845 | 1320 | 0 | NO |
| C393 | C402H22 | SCD22U10V2KX-1GP | 78.22423.5FL | C402H22 | 5880 | 1320 | 0 | NO |
| C394 | C402H22 | SCD22U10V2KX-1GP | 78.22423.5FL | C402H22 | 6008 | 1319 | 0 | NO |
| C395 | C402H22 | SCD22U10V2KX-1GP | 78.22423.5FL | C402H22 | 6043 | 1319 | 0 | NO |
| C396 | C402H22 | SCD22U10V2KX-1GP | 78.22423.5FL | C402H22 | 6425 | 1320 | 0 | NO |
| C397 | C402H22 | SCD22U10V2KX-1GP | 78.22423.5FL | C402H22 | 6460 | 1320 | 0 | NO |
| C398 | C402H22 | SCD22U10V2KX-1GP | 78.22423.5FL | C402H22 | 6241.76 | 1320 | 0 | NO |
| C399 | C402H22 | SCD22U10V2KX-1GP | 78.22423.5FL | C402H22 | 6276.76 | 1320 | 0 | NO |
| C400 | C402H22 | SCD22U10V2KX-1GP | 78.22423.5FL | C402H22 | 6345 | 1320 | 0 | NO |
| C401 | C402H22 | SCD22U10V2KX-1GP | 78.22423.5FL | C402H22 | 6380 | 1320 | 0 | NO |
| C402 | C402H22 | SCD22U10V2KX-1GP | 78.22423.5FL | C402H22 | 7150 | 1140 | 270 | NO |
| C403 | C402H22 | SCD22U10V2KX-1GP | 78.22423.5FL | C402H22 | 7150 | 1175 | 270 | NO |
| C404 | C402H22 | SCD22U10V2KX-1GP | 78.22423.5FL | C402H22 | 7150 | 885 | 270 | NO |
| C405 | C402H22 | SCD22U10V2KX-1GP | 78.22423.5FL | C402H22 | 7150 | 850 | 270 | NO |
| C406 | C402H22 | SCD22U10V2KX-1GP | 78.22423.5FL | C402H22 | 7150 | 1020 | 270 | NO |
| C407 | C402H22 | SCD22U10V2KX-1GP | 78.22423.5FL | C402H22 | 7150 | 1055 | 270 | NO |
| C408 | C402H22 | SCD22U10V2KX-1GP | 78.22423.5FL | C402H22 | 7150 | 930 | 270 | NO |
| C409 | C402H22 | SCD22U10V2KX-1GP | 78.22423.5FL | C402H22 | 7150 | 965 | 270 | NO |
| C410 | C402H22 | SCD22U10V2KX-1GP | 78.22423.5FL | C402H22 | 7150 | 780 | 270 | NO |
| C411 | C402H22 | SCD22U10V2KX-1GP | 78.22423.5FL | C402H22 | 7150 | 815 | 270 | NO |
| C412 | C402H24 | SC12P50V2JN-3GP | 78.12034.1FL | C402H24 | 6095 | 3553.83 | 180 | NO |
| C413 | C402H24 | SC12P50V2JN-3GP | 78.12034.1FL | C402H24 | 6095 | 3661.13 | 0 | NO |
| C414 | C402H22 | SCD1U16V2KX-3GP | 78.10421.2FL | C402H22 | 1093 | 2033 | 270 | NO |
| C415 | C402H22 | SCD1U25V2KX-2-GP | 78.10422.2FL | C402H22 | 3061.78 | 7344.31 | 0 | YES |
| C416 | C402H22 | SCD1U25V2KX-2-GP | 78.10422.2FL | C402H22 | 8626.7800000000007 | 7639.31 | 0 | YES |
| C417 | C402H22 | SCD1U25V2KX-2-GP | 78.10422.2FL | C402H22 | 12946.28 | 7278.67 | 180 | NO |
| C418 | C402H22 | SCD1U25V2KX-2-GP | 78.10422.2FL | C402H22 | 5190.6899999999996 | 7869.67 | 0 | YES |
| C419 | C402H22 | SCD015U25V2KX-GP | 78.15322.2FL | C402H22 | 746 | 7293 | 0 | NO |
| C420 | C402H22 | SCD1U16V2KX-3GP | 78.10421.2FL | C402H22 | 1040.5 | 1334.6 | 0 | NO |
| C421 | C402H22 | SCD1U16V2KX-3GP | 78.10421.2FL | C402H22 | 315 | 2187 | 180 | NO |
| C422 | C402H22 | SCD1U16V2KX-3GP | 78.10421.2FL | C402H22 | 231 | 2187 | 180 | NO |
| C423 | C805H58 | SC47U4V5MX-2-GP | 78.4761T.81L | C805H58 | 351 | 2688 | 270 | YES |
| C424 | C805H54 | SC10U16V5KX-1-GP | 78.10621.81L | C805H54 | 11680 | 2248 | 0 | NO |
| C425 | C805H54 | SC10U16V5KX-1-GP | 78.10621.81L | C805H54 | 11770 | 2248 | 0 | NO |
| C426 | C805H54 | SC10U16V5KX-1-GP | 78.10621.81L | C805H54 | 11860 | 2248 | 0 | NO |
| C427 | C805H54 | SC10U16V5KX-1-GP | 78.10621.81L | C805H54 | 11950 | 2248 | 0 | NO |
| C428 | C0201H13 | SCD1U16V1KX-1-GP | 078.10421.09S1 | C0201H13 | 9492 | 1732.18 | 270 | YES |
| C429 | C0201H13 | SCD1U16V1KX-1-GP | 078.10421.09S1 | C0201H13 | 9416 | 1732.18 | 90 | YES |
| C430 | C805H58 | SC10U6D3V5KX-4GP | 78.10620.21L | C805H58 | 360 | 3083 | 270 | YES |
| C431 | C805H54 | SC10U16V5KX-1-GP | 78.10621.81L | C805H54 | 12040 | 2248 | 0 | NO |
| C432 | C0201H13 | SCD1U16V1KX-1-GP | 078.10421.09S1 | C0201H13 | 9337 | 1732.18 | 90 | YES |
| C433 | C0201H13 | SCD1U16V1KX-1-GP | 078.10421.09S1 | C0201H13 | 9256 | 1732.18 | 90 | YES |
| C434 | C0201H13 | SCD1U16V1KX-1-GP | 078.10421.09S1 | C0201H13 | 9416 | 1653.38 | 90 | YES |
| C435 | C0201H13 | SCD1U16V1KX-1-GP | 078.10421.09S1 | C0201H13 | 9337 | 1653.38 | 90 | YES |
| C436 | C0201H13 | SCD1U16V1KX-1-GP | 078.10421.09S1 | C0201H13 | 9256 | 1653.38 | 270 | YES |
| C437 | C0201H13 | SCD1U16V1KX-1-GP | 078.10421.09S1 | C0201H13 | 9492 | 1653.38 | 270 | YES |
| C438 | C0201H13 | SCD1U16V1KX-1-GP | 078.10421.09S1 | C0201H13 | 9572 | 1653.38 | 270 | YES |
| C439 | C805H54 | SC10U16V5KX-1-GP | 78.10621.81L | C805H54 | 12130 | 2248 | 0 | NO |
| C440 | C0201H13 | SCD1U16V1KX-1-GP | 078.10421.09S1 | C0201H13 | 9572 | 2126 | 90 | YES |
| C441 | C0201H13 | SCD1U16V1KX-1-GP | 078.10421.09S1 | C0201H13 | 9492 | 2126 | 90 | YES |
| C442 | C0201H13 | SCD1U16V1KX-1-GP | 078.10421.09S1 | C0201H13 | 9729 | 2047 | 90 | YES |
| C443 | C0201H13 | SCD1U16V1KX-1-GP | 078.10421.09S1 | C0201H13 | 9651 | 2047 | 90 | YES |
| C444 | C0201H13 | SCD1U16V1KX-1-GP | 078.10421.09S1 | C0201H13 | 9572 | 2047 | 90 | YES |
| C445 | C0201H13 | SCD1U16V1KX-1-GP | 078.10421.09S1 | C0201H13 | 9729 | 1929 | 270 | YES |
| C446 | C0201H13 | SCD1U16V1KX-1-GP | 078.10421.09S1 | C0201H13 | 9651 | 1929 | 270 | YES |
| C447 | C0201H13 | SCD1U16V1KX-1-GP | 078.10421.09S1 | C0201H13 | 9572 | 1929 | 270 | YES |
| C448 | C0201H13 | SCD1U16V1KX-1-GP | 078.10421.09S1 | C0201H13 | 9492 | 1851.68 | 90 | YES |
| C449 | C0201H13 | SCD1U16V1KX-1-GP | 078.10421.09S1 | C0201H13 | 9729 | 1732.18 | 270 | YES |
| C450 | C0201H13 | SCD1U16V1KX-1-GP | 078.10421.09S1 | C0201H13 | 9651 | 1732.18 | 270 | YES |
| C451 | C0201H13 | SCD1U16V1KX-1-GP | 078.10421.09S1 | C0201H13 | 9572 | 1732.18 | 270 | YES |
| C452 | C0201H13 | SCD1U16V1KX-1-GP | 078.10421.09S1 | C0201H13 | 9729 | 1851.68 | 270 | YES |
| C453 | C0201H13 | SCD1U16V1KX-1-GP | 078.10421.09S1 | C0201H13 | 9729 | 1653.38 | 270 | YES |
| C454 | C805H58 | SC100U4V5MX-1-GP | 078.1071T.0811 | C805H58 | 11680 | 2710 | 180 | NO |
| C455 | C805H58 | SC100U4V5MX-1-GP | 078.1071T.0811 | C805H58 | 11770 | 2710 | 180 | NO |
| C456 | C805H58 | SC100U4V5MX-1-GP | 078.1071T.0811 | C805H58 | 11860 | 2710 | 180 | NO |
| C457 | C0201H13 | SCD1U16V1KX-1-GP | 078.10421.09S1 | C0201H13 | 9651 | 1653.38 | 270 | YES |
| C458 | C805H54 | SC10U16V5KX-1-GP | 78.10621.81L | C805H54 | 11950 | 2710 | 180 | NO |
| C459 | C805H58 | SC100U4V5MX-1-GP | 078.1071T.0811 | C805H58 | 12040 | 2710 | 180 | NO |
| C460 | C0201H13 | SCD1U16V1KX-1-GP | 078.10421.09S1 | C0201H13 | 9492 | 2047 | 90 | YES |
| C461 | C0201H13 | SCD1U16V1KX-1-GP | 078.10421.09S1 | C0201H13 | 9651 | 1851.68 | 270 | YES |
| C462 | C0201H13 | SCD1U16V1KX-1-GP | 078.10421.09S1 | C0201H13 | 9572 | 1851.68 | 90 | YES |
| C463 | C805H56 | SC4D7U16V5KX-1-GP | 78.47521.21L | C805H56 | 9794 | 526 | 180 | NO |
| C464 | C805H56 | SC4D7U16V5KX-1-GP | 78.47521.21L | C805H56 | 9714 | 526 | 180 | NO |
| C465 | C805H58 | SC47U4V5MX-2-GP | 78.4761T.81L | C805H58 | 9239 | 516 | 180 | NO |
| C466 | C0201H13 | SCD1U16V1KX-1-GP | 078.10421.09S1 | C0201H13 | 9393 | 1417 | 90 | YES |
| C467 | C0201H13 | SCD1U16V1KX-1-GP | 078.10421.09S1 | C0201H13 | 9352 | 1299 | 270 | YES |
| C468 | C0201H13 | SCD1U16V1KX-1-GP | 078.10421.09S1 | C0201H13 | 9499 | 1496 | 270 | YES |
| C469 | C0201H13 | SCD1U16V1KX-1-GP | 078.10421.09S1 | C0201H13 | 9827.2800000000007 | 1260 | 0 | YES |
| C470 | C805H56 | SC4D7U16V5KX-1-GP | 78.47521.21L | C805H56 | 9794 | 356 | 0 | NO |
| C471 | C0201H13 | SCD1U16V1KX-1-GP | 078.10421.09S1 | C0201H13 | 9747.68 | 1260 | 0 | YES |
| C472 | C0201H13 | SCD1U16V1KX-1-GP | 078.10421.09S1 | C0201H13 | 9669 | 1260 | 0 | YES |
| C473 | C0201H13 | SCD1U16V1KX-1-GP | 078.10421.09S1 | C0201H13 | 9585 | 1260 | 90 | YES |
| C474 | C0201H13 | SCD1U16V1KX-1-GP | 078.10421.09S1 | C0201H13 | 9541 | 1378 | 270 | YES |
| C475 | C0201H13 | SCD1U16V1KX-1-GP | 078.10421.09S1 | C0201H13 | 9315.32 | 1259 | 0 | YES |
| C476 | C0201H13 | SCD1U16V1KX-1-GP | 078.10421.09S1 | C0201H13 | 9236 | 1259 | 0 | YES |
| C477 | C805H56 | SC4D7U16V5KX-1-GP | 78.47521.21L | C805H56 | 9714 | 356 | 0 | NO |
| C478 | C0201H13 | SCD1U16V1KX-1-GP | 078.10421.09S1 | C0201H13 | 9157.93 | 1259 | 0 | YES |
| C479 | C0201H13 | SCD1U16V1KX-1-GP | 078.10421.09S1 | C0201H13 | 9079 | 1259 | 0 | YES |
| C480 | C0201H13 | SCD1U16V1KX-1-GP | 078.10421.09S1 | C0201H13 | 9108 | 1378 | 270 | YES |
| C481 | C0201H13 | SCD1U16V1KX-1-GP | 078.10421.09S1 | C0201H13 | 9247.5 | 1496.2 | 270 | YES |
| C482 | C0201H13 | SCD1U16V1KX-1-GP | 078.10421.09S1 | C0201H13 | 9394.5 | 1575 | 90 | YES |
| C483 | C0201H13 | SCD1U16V1KX-1-GP | 078.10421.09S1 | C0201H13 | 9720 | 1496 | 90 | YES |
| C484 | C0201H13 | SCD1U16V1KX-1-GP | 078.10421.09S1 | C0201H13 | 9651.5 | 1614 | 90 | YES |
| C485 | C0201H13 | SCD1U16V1KX-1-GP | 078.10421.09S1 | C0201H13 | 9464 | 1603 | 180 | YES |
| C486 | C0201H13 | SCD1U16V1KX-1-GP | 078.10421.09S1 | C0201H13 | 9532.68 | 1574.68 | 270 | YES |
| C487 | C0201H13 | SCD1U16V1KX-1-GP | 078.10421.09S1 | C0201H13 | 9836 | 1378 | 90 | YES |
| C488 | C0201H13 | SCD1U16V1KX-1-GP | 078.10421.09S1 | C0201H13 | 9825 | 2165.0500000000002 | 90 | YES |
| C489 | C0201H13 | SCD1U16V1KX-1-GP | 078.10421.09S1 | C0201H13 | 9001 | 1771.68 | 90 | YES |
| C490 | C0201H13 | SCD1U16V1KX-1-GP | 078.10421.09S1 | C0201H13 | 9001 | 1810.68 | 90 | YES |
| C491 | C0201H13 | SCD1U16V1KX-1-GP | 078.10421.09S1 | C0201H13 | 9052 | 1852 | 90 | YES |
| C492 | C0201H13 | SCD1U16V1KX-1-GP | 078.10421.09S1 | C0201H13 | 9001 | 1889.68 | 90 | YES |
| C493 | C0201H13 | SCD1U16V1KX-1-GP | 078.10421.09S1 | C0201H13 | 9001 | 1929.18 | 90 | YES |
| C494 | C805H58 | SC100U4V5MX-1-GP | 078.1071T.0811 | C805H58 | 9265 | 2750 | 270 | YES |
| C495 | C805H58 | SC100U4V5MX-1-GP | 078.1071T.0811 | C805H58 | 9690 | 2755 | 90 | YES |
| C496 | C805H56 | SC4D7U16V5KX-1-GP | 78.47521.21L | C805H56 | 9265 | 2830 | 270 | YES |
| C497 | C0201H13 | SCD1U16V1KX-1-GP | 078.10421.09S1 | C0201H13 | 9824.5 | 1850.5 | 90 | YES |
| C498 | C0201H13 | SCD1U16V1KX-1-GP | 078.10421.09S1 | C0201H13 | 9532.68 | 1614.68 | 270 | YES |
| C499 | C0201H13 | SCD1U16V1KX-1-GP | 078.10421.09S1 | C0201H13 | 9118 | 1811 | 270 | YES |
| C500 | C0201H13 | SCD1U16V1KX-1-GP | 078.10421.09S1 | C0201H13 | 9512 | 2283.27 | 90 | YES |
| C501 | C0201H13 | SCD1U16V1KX-1-GP | 078.10421.09S1 | C0201H13 | 9669 | 2283 | 90 | YES |
| C502 | C0201H13 | SCD1U16V1KX-1-GP | 078.10421.09S1 | C0201H13 | 9512 | 2205 | 90 | YES |
| C503 | C0201H13 | SCD1U16V1KX-1-GP | 078.10421.09S1 | C0201H13 | 9275 | 2283.27 | 270 | YES |
| C504 | C0201H13 | SCD1U16V1KX-1-GP | 078.10421.09S1 | C0201H13 | 9669 | 2362 | 90 | YES |
| C505 | C0201H13 | SCD1U16V1KX-1-GP | 078.10421.09S1 | C0201H13 | 9590 | 2362.1 | 90 | YES |
| C506 | C0201H13 | SCD1U16V1KX-1-GP | 078.10421.09S1 | C0201H13 | 9669 | 2323 | 270 | YES |
| C507 | C805H56 | SC4D7U16V5KX-1-GP | 78.47521.21L | C805H56 | 9690 | 2675 | 90 | YES |
| C508 | C0201H13 | SCD1U16V1KX-1-GP | 078.10421.09S1 | C0201H13 | 9590 | 2323 | 270 | YES |
| C509 | C0201H13 | SCD1U16V1KX-1-GP | 078.10421.09S1 | C0201H13 | 9512 | 2323 | 270 | YES |
| C510 | C0201H13 | SCD1U16V1KX-1-GP | 078.10421.09S1 | C0201H13 | 9589 | 2205 | 90 | YES |
| C511 | C0201H13 | SCD1U16V1KX-1-GP | 078.10421.09S1 | C0201H13 | 9590 | 2283.27 | 90 | YES |
| C512 | C0201H13 | SCD1U16V1KX-1-GP | 078.10421.09S1 | C0201H13 | 9669 | 2244 | 270 | YES |
| C513 | C0201H13 | SCD1U16V1KX-1-GP | 078.10421.09S1 | C0201H13 | 9512 | 2244 | 270 | YES |
| C514 | C0201H13 | SCD1U16V1KX-1-GP | 078.10421.09S1 | C0201H13 | 9590 | 2244 | 270 | YES |
| C515 | C0201H13 | SCD1U16V1KX-1-GP | 078.10421.09S1 | C0201H13 | 9118 | 2165 | 270 | YES |
| C516 | C805H56 | SC4D7U16V5KX-1-GP | 78.47521.21L | C805H56 | 9265 | 2670 | 270 | YES |
| C517 | C805H56 | SC4D7U16V5KX-1-GP | 78.47521.21L | C805H56 | 9690 | 2835 | 90 | YES |
| C518 | C805H58 | SC47U4V5MX-2-GP | 78.4761T.81L | C805H58 | 7482.37 | 2021.92 | 0 | NO |
| C519 | C0201H13 | SCD1U16V1KX-1-GP | 078.10421.09S1 | C0201H13 | 9275 | 2244 | 90 | YES |
| C520 | C0201H13 | SCD1U16V1KX-1-GP | 078.10421.09S1 | C0201H13 | 9355 | 2244 | 90 | YES |
| C521 | C0201H13 | SCD1U16V1KX-1-GP | 078.10421.09S1 | C0201H13 | 9275 | 2204.8000000000002 | 270 | YES |
| C522 | C0201H13 | SCD1U16V1KX-1-GP | 078.10421.09S1 | C0201H13 | 9355 | 2204.8000000000002 | 270 | YES |
| C523 | C0201H13 | SCD1U16V1KX-1-GP | 078.10421.09S1 | C0201H13 | 9668 | 2205 | 90 | YES |
| C524 | C0201H13 | SCD1U16V1KX-1-GP | 078.10421.09S1 | C0201H13 | 9355 | 2283.27 | 270 | YES |
| C525 | C0201H13 | SCD1U16V1KX-1-GP | 078.10421.09S1 | C0201H13 | 9275 | 2362.1 | 270 | YES |
| C526 | C0201H13 | SCD1U16V1KX-1-GP | 078.10421.09S1 | C0201H13 | 9355 | 2362.1 | 270 | YES |
| C527 | C0201H13 | SCD1U16V1KX-1-GP | 078.10421.09S1 | C0201H13 | 9512 | 2362.1 | 90 | YES |
| C528 | C0201H13 | SCD1U16V1KX-1-GP | 078.10421.09S1 | C0201H13 | 9275 | 2323 | 90 | YES |
| C529 | C0201H13 | SCD1U16V1KX-1-GP | 078.10421.09S1 | C0201H13 | 9355 | 2323 | 90 | YES |
| C530 | C0201H13 | SCD1U16V1KX-1-GP | 078.10421.09S1 | C0201H13 | 9406 | 2323 | 270 | YES |
| C531 | C0201H13 | SCD1U16V1KX-1-GP | 078.10421.09S1 | C0201H13 | 9406 | 2244 | 270 | YES |
| C532 | C805H56 | SC4D7U16V5KX-1-GP | 78.47521.21L | C805H56 | 7275 | 2820 | 180 | YES |
| C533 | C0201H13 | SCD1U16V1KX-1-GP | 078.10421.09S1 | C0201H13 | 9001 | 2322.6799999999998 | 90 | YES |
| C534 | C0201H13 | SCD1U16V1KX-1-GP | 078.10421.09S1 | C0201H13 | 9001 | 2283.1799999999998 | 90 | YES |
| C535 | C0201H13 | SCD1U16V1KX-1-GP | 078.10421.09S1 | C0201H13 | 9001 | 2243.6799999999998 | 90 | YES |
| C536 | C0201H13 | SCD1U16V1KX-1-GP | 078.10421.09S1 | C0201H13 | 9001 | 2204.6799999999998 | 90 | YES |
| C537 | C0201H13 | SCD1U16V1KX-1-GP | 078.10421.09S1 | C0201H13 | 9001 | 2165.1799999999998 | 90 | YES |
| C538 | C0201H13 | SCD1U16V1KX-1-GP | 078.10421.09S1 | C0201H13 | 9001 | 2125.6799999999998 | 90 | YES |
| C539 | C0201H13 | SCD1U16V1KX-1-GP | 078.10421.09S1 | C0201H13 | 9001 | 2362 | 90 | YES |
| C540 | C805H56 | SC4D7U16V5KX-1-GP | 78.47521.21L | C805H56 | 7351 | 2820 | 180 | YES |
| C541 | C0201H13 | SCD1U16V1KX-1-GP | 078.10421.09S1 | C0201H13 | 9236.0400000000009 | 2368 | 0 | YES |
| C542 | C0201H13 | SCD1U16V1KX-1-GP | 078.10421.09S1 | C0201H13 | 9118 | 2367 | 0 | YES |
| C543 | C0201H13 | SCD1U16V1KX-1-GP | 078.10421.09S1 | C0201H13 | 9078.93 | 2367 | 0 | YES |
| C544 | C0201H13 | SCD1U16V1KX-1-GP | 078.10421.09S1 | C0201H13 | 8920 | 2362 | 270 | YES |
| C545 | C0201H13 | SCD1U16V1KX-1-GP | 078.10421.09S1 | C0201H13 | 9194 | 2165.5 | 90 | YES |
| C546 | C0201H13 | SCD1U16V1KX-1-GP | 078.10421.09S1 | C0201H13 | 9157.68 | 1789.68 | 0 | YES |
| C547 | C0201H13 | SCD1U16V1KX-1-GP | 078.10421.09S1 | C0201H13 | 9313.5 | 1575 | 90 | YES |
| C548 | C0201H13 | SCD1U16V1KX-1-GP | 078.10421.09S1 | C0201H13 | 9945 | 2322.6799999999998 | 270 | YES |
| C549 | C805H56 | SC4D7U16V5KX-1-GP | 78.47521.21L | C805H56 | 7351 | 2820 | 180 | NO |
| C550 | C0201H13 | SCD1U16V1KX-1-GP | 078.10421.09S1 | C0201H13 | 9945 | 2046.68 | 270 | YES |
| C551 | C0201H13 | SCD1U16V1KX-1-GP | 078.10421.09S1 | C0201H13 | 9945 | 2007.68 | 270 | YES |
| C552 | C805H56 | SC4D7U16V5KX-1-GP | 78.47521.21L | C805H56 | 7275 | 2820 | 180 | NO |
| C553 | C805H56 | SC4D7U16V5KX-1-GP | 78.47521.21L | C805H56 | 7199 | 2820 | 180 | NO |
| C554 | C805H56 | SC4D7U16V5KX-1-GP | 78.47521.21L | C805H56 | 7123 | 2820 | 180 | NO |
| C555 | C0201H13 | SCD1U16V1KX-1-GP | 078.10421.09S1 | C0201H13 | 9984 | 1417.68 | 90 | YES |
| C556 | C0201H13 | SCD1U16V1KX-1-GP | 078.10421.09S1 | C0201H13 | 8964 | 1574.99 | 270 | YES |
| C557 | C0201H13 | SCD1U16V1KX-1-GP | 078.10421.09S1 | C0201H13 | 8964 | 1614.36 | 270 | YES |
| C558 | C805H56 | SC4D7U16V5KX-1-GP | 78.47521.21L | C805H56 | 7047 | 2820 | 180 | NO |
| C559 | C805H56 | SC4D7U16V5KX-1-GP | 78.47521.21L | C805H56 | 7086 | 2425 | 0 | NO |
| C560 | C805H56 | SC4D7U16V5KX-1-GP | 78.47521.21L | C805H56 | 7166 | 2425 | 0 | NO |
| C561 | C0201H13 | SCD1U16V1KX-1-GP | 078.10421.09S1 | C0201H13 | 9001 | 2047.18 | 90 | YES |
| C562 | C0201H13 | SCD1U16V1KX-1-GP | 078.10421.09S1 | C0201H13 | 9001 | 2007.68 | 90 | YES |
| C563 | C0201H13 | SCD1U16V1KX-1-GP | 078.10421.09S1 | C0201H13 | 9001 | 2086.6799999999998 | 90 | YES |
| C564 | C805H56 | SC4D7U16V5KX-1-GP | 78.47521.21L | C805H56 | 7246 | 2425 | 0 | NO |
| C565 | C0201H13 | SCD1U16V1KX-1-GP | 078.10421.09S1 | C0201H13 | 8964 | 1299.03 | 270 | YES |
| C566 | C0201H13 | SCD1U16V1KX-1-GP | 078.10421.09S1 | C0201H13 | 8964 | 1338.77 | 270 | YES |
| C567 | C0201H13 | SCD1U16V1KX-1-GP | 078.10421.09S1 | C0201H13 | 8964 | 1378 | 270 | YES |
| C568 | C0201H13 | SCD1U16V1KX-1-GP | 078.10421.09S1 | C0201H13 | 8964 | 1417.14 | 270 | YES |
| C569 | C0201H13 | SCD1U16V1KX-1-GP | 078.10421.09S1 | C0201H13 | 8964 | 1456.88 | 270 | YES |
| C570 | C0201H13 | SCD1U16V1KX-1-GP | 078.10421.09S1 | C0201H13 | 8964 | 1496 | 270 | YES |
| C571 | C0201H13 | SCD1U16V1KX-1-GP | 078.10421.09S1 | C0201H13 | 8964 | 1535.62 | 270 | YES |
| C572 | C805H56 | SC4D7U16V5KX-1-GP | 78.47521.21L | C805H56 | 7326 | 2425 | 0 | NO |
| C573 | C0201H13 | SCD1U16V1KX-1-GP | 078.10421.09S1 | C0201H13 | 9001 | 1732.18 | 90 | YES |
| C574 | C0201H13 | SCD1U16V1KX-1-GP | 078.10421.09S1 | C0201H13 | 9001 | 1692.68 | 90 | YES |
| C575 | C0201H13 | SCD1U16V1KX-1-GP | 078.10421.09S1 | C0201H13 | 9061 | 1653 | 90 | YES |
| C576 | C0201H13 | SCD1U16V1KX-1-GP | 078.10421.09S1 | C0201H13 | 9017.68 | 1614.68 | 90 | YES |
| C577 | C0201H13 | SCD1U16V1KX-1-GP | 078.10421.09S1 | C0201H13 | 9001 | 1968.18 | 90 | YES |
| C578 | C0201H13 | SCD1U16V1KX-1-GP | 078.10421.09S1 | C0201H13 | 9945 | 2362 | 270 | YES |
| C579 | C0201H13 | SCD1U16V1KX-1-GP | 078.10421.09S1 | C0201H13 | 9945 | 2204.6799999999998 | 270 | YES |
| C580 | C0201H13 | SCD1U16V1KX-1-GP | 078.10421.09S1 | C0201H13 | 9945 | 2165.1799999999998 | 270 | YES |
| C581 | C0201H13 | SCD1U16V1KX-1-GP | 078.10421.09S1 | C0201H13 | 9945 | 2125.6799999999998 | 270 | YES |
| C582 | C0201H13 | SCD1U16V1KX-1-GP | 078.10421.09S1 | C0201H13 | 9945 | 2086.6799999999998 | 270 | YES |
| C583 | C805H56 | SC4D7U16V5KX-1-GP | 78.47521.21L | C805H56 | 7326 | 2425 | 0 | YES |
| C584 | C805H56 | SC4D7U16V5KX-1-GP | 78.47521.21L | C805H56 | 7246 | 2425 | 0 | YES |
| C585 | C805H56 | SC4D7U16V5KX-1-GP | 78.47521.21L | C805H56 | 7166 | 2425 | 0 | YES |
| C586 | C805H56 | SC4D7U16V5KX-1-GP | 78.47521.21L | C805H56 | 7086 | 2425 | 0 | YES |
| C587 | C0201H13 | SCD1U16V1KX-1-GP | 078.10421.09S1 | C0201H13 | 9945 | 2283.6799999999998 | 270 | YES |
| C588 | C0201H13 | SCD1U16V1KX-1-GP | 078.10421.09S1 | C0201H13 | 9905 | 1654 | 270 | YES |
| C589 | C0201H13 | SCD1U16V1KX-1-GP | 078.10421.09S1 | C0201H13 | 10002.68 | 1614.68 | 90 | YES |
| C590 | C0201H13 | SCD1U16V1KX-1-GP | 078.10421.09S1 | C0201H13 | 9944 | 1575 | 270 | YES |
| C591 | C0201H13 | SCD1U16V1KX-1-GP | 078.10421.09S1 | C0201H13 | 9984 | 1536 | 90 | YES |
| C592 | C0201H13 | SCD1U16V1KX-1-GP | 078.10421.09S1 | C0201H13 | 9984 | 1496.18 | 90 | YES |
| C593 | C0201H13 | SCD1U16V1KX-1-GP | 078.10421.09S1 | C0201H13 | 9984 | 1456.68 | 90 | YES |
| C594 | C0201H13 | SCD1U16V1KX-1-GP | 078.10421.09S1 | C0201H13 | 9749.5 | 2165.1 | 270 | YES |
| C595 | C0201H13 | SCD1U16V1KX-1-GP | 078.10421.09S1 | C0201H13 | 9750 | 1771.5 | 270 | YES |
| C596 | C0201H13 | SCD1U16V1KX-1-GP | 078.10421.09S1 | C0201H13 | 9826 | 1771.5 | 90 | YES |
| C597 | C0201H13 | SCD1U16V1KX-1-GP | 078.10421.09S1 | C0201H13 | 10022 | 2362 | 90 | YES |
| C598 | C0201H13 | SCD1U16V1KX-1-GP | 078.10421.09S1 | C0201H13 | 9197 | 2367 | 0 | YES |
| C599 | C0201H13 | SCD1U16V1KX-1-GP | 078.10421.09S1 | C0201H13 | 9866 | 2365 | 0 | YES |
| C600 | C0201H13 | SCD1U16V1KX-1-GP | 078.10421.09S1 | C0201H13 | 9826.9699999999993 | 2365 | 0 | YES |
| C601 | C0201H13 | SCD1U16V1KX-1-GP | 078.10421.09S1 | C0201H13 | 9787.6 | 2365 | 0 | YES |
| C602 | C0201H13 | SCD1U16V1KX-1-GP | 078.10421.09S1 | C0201H13 | 9748 | 2365 | 0 | YES |
| C603 | C0201H13 | SCD1U16V1KX-1-GP | 078.10421.09S1 | C0201H13 | 9708.4500000000007 | 2365 | 0 | YES |
| C604 | C0201H13 | SCD1U16V1KX-1-GP | 078.10421.09S1 | C0201H13 | 9157.2999999999993 | 2367 | 0 | YES |
| C605 | C0201H13 | SCD1U16V1KX-1-GP | 078.10421.09S1 | C0201H13 | 9984 | 1299 | 90 | YES |
| C606 | C0201H13 | SCD1U16V1KX-1-GP | 078.10421.09S1 | C0201H13 | 9984 | 1377.68 | 90 | YES |
| C607 | C0201H13 | SCD1U16V1KX-1-GP | 078.10421.09S1 | C0201H13 | 9945 | 2243.6799999999998 | 270 | YES |
| C608 | C0201H13 | SCD1U16V1KX-1-GP | 078.10421.09S1 | C0201H13 | 9945 | 1968.68 | 270 | YES |
| C609 | C0201H13 | SCD1U16V1KX-1-GP | 078.10421.09S1 | C0201H13 | 9945 | 1928.68 | 270 | YES |
| C610 | C0201H13 | SCD1U16V1KX-1-GP | 078.10421.09S1 | C0201H13 | 9945 | 1889.68 | 270 | YES |
| C611 | C0201H13 | SCD1U16V1KX-1-GP | 078.10421.09S1 | C0201H13 | 9895 | 1855 | 270 | YES |
| C612 | C0201H13 | SCD1U16V1KX-1-GP | 078.10421.09S1 | C0201H13 | 9945 | 1810.68 | 270 | YES |
| C613 | C0201H13 | SCD1U16V1KX-1-GP | 078.10421.09S1 | C0201H13 | 9945 | 1771.68 | 270 | YES |
| C614 | C0201H13 | SCD1U16V1KX-1-GP | 078.10421.09S1 | C0201H13 | 9945 | 1732.68 | 270 | YES |
| C615 | C0201H13 | SCD1U16V1KX-1-GP | 078.10421.09S1 | C0201H13 | 9945 | 1692.68 | 270 | YES |
| C616 | C0201H13 | SCD1U16V1KX-1-GP | 078.10421.09S1 | C0201H13 | 9945 | 1614 | 270 | YES |
| C617 | C805H56 | SC4D7U16V5KX-1-GP | 78.47521.21L | C805H56 | 7047 | 2820 | 180 | YES |
| C618 | C805H56 | SC4D7U16V5KX-1-GP | 78.47521.21L | C805H56 | 7123 | 2820 | 180 | YES |
| C619 | C805H56 | SC4D7U16V5KX-1-GP | 78.47521.21L | C805H56 | 7199 | 2820 | 180 | YES |
| C620 | C402H22 | SCD1U16V2KX-3GP | 78.10421.2FL | C402H22 | 484 | 2710 | 0 | NO |
| C621 | C402H22 | SCD1U16V2KX-3GP | 78.10421.2FL | C402H22 | 531.70000000000005 | 3018.16 | 90 | YES |
| C622 | C402H22 | SCD1U16V2KX-3GP | 78.10421.2FL | C402H22 | 531.77 | 2983.71 | 90 | YES |
| C623 | C402H22 | SCD1U16V2KX-3GP | 78.10421.2FL | C402H22 | 415 | 2635 | 180 | NO |
| C624 | C805H58 | SC10U6D3V5KX-4GP | 78.10620.21L | C805H58 | 359 | 2785 | 270 | YES |
| C625 | C805H54 | SC47U6D3V5MX-1-GP | 78.47610.51L | C805H54 | 1018.2 | 3071.2 | 90 | YES |
| C626 | C805H58 | SC10U6D3V5KX-4GP | 78.10620.21L | C805H58 | 854 | 2646 | 0 | YES |
| C627 | C805H58 | SC10U6D3V5KX-4GP | 78.10620.21L | C805H58 | 508 | 3385 | 180 | YES |
| C628 | C402H22 | SCD1U16V2KX-3GP | 78.10421.2FL | C402H22 | 676 | 3291 | 180 | NO |
| C629 | C402H22 | SCD1U16V2KX-3GP | 78.10421.2FL | C402H22 | 531.78 | 2949.34 | 90 | YES |
| C630 | C805H54 | SC10U16V5KX-1-GP | 78.10621.81L | C805H54 | 12125 | 2710 | 180 | NO |
| C631 | C402H22 | SCD1U16V2KX-3GP | 78.10421.2FL | C402H22 | 890.3 | 2738 | 90 | NO |
| C632 | C402H22 | SCD1U16V2KX-3GP | 78.10421.2FL | C402H22 | 1026 | 3067 | 90 | NO |
| C633 | C805H58 | SC47U4V5MX-2-GP | 78.4761T.81L | C805H58 | 609 | 3151 | 90 | YES |
| C634 | C805H58 | SC10U6D3V5KX-4GP | 78.10620.21L | C805H58 | 859.76 | 2912.98 | 270 | YES |
| C635 | C402H22 | SCD1U16V2KX-3GP | 78.10421.2FL | C402H22 | 530 | 3071 | 90 | YES |
| C636 | C402H22 | SCD1U16V2KX-3GP | 78.10421.2FL | C402H22 | 635.82000000000005 | 2952.07 | 90 | YES |
| C637 | C402H22 | SCD1U16V2KX-3GP | 78.10421.2FL | C402H22 | 723 | 2637 | 0 | NO |
| C638 | C402H22 | SCD1U16V2KX-3GP | 78.10421.2FL | C402H22 | 546 | 3234 | 180 | NO |
| C639 | C402H22 | SCD22U10V2KX-1GP | 78.22423.5FL | C402H22 | 8369.86 | 1616.91 | 270 | NO |
| C640 | C805H58 | SC10U6D3V5KX-4GP | 78.10620.21L | C805H58 | 875.61 | 3215.27 | 180 | YES |
| C641 | C402H22 | SCD22U10V2KX-1GP | 78.22423.5FL | C402H22 | 8369.86 | 1582.4 | 270 | NO |
| C642 | C402H22 | SCD22U10V2KX-1GP | 78.22423.5FL | C402H22 | 847 | 3300 | 180 | NO |
| C643 | C402H22 | SCD22U10V2KX-1GP | 78.22423.5FL | C402H22 | 813 | 3300 | 180 | NO |
| C688 | C402H22 | SCD1U16V2KX-3GP | 78.10421.2FL | C402H22 | 4592 | 3743 | 0 | NO |
| C689 | C603H36 | SC220P50V3JN-GP | 78.22134.1BL | C603H36 | 1747 | 7279 | 90 | NO |
| C690 | C603H36 | SC220P50V3JN-GP | 78.22134.1BL | C603H36 | 1747 | 7489 | 90 | NO |
| C691 | C603H36 | SC220P50V3JN-GP | 78.22134.1BL | C603H36 | 1642 | 7489 | 270 | NO |
| C692 | C603H36 | SC220P50V3JN-GP | 78.22134.1BL | C603H36 | 1642 | 7279 | 270 | NO |
| C693 | C402H22 | SCD01U50V2KX-1GP | 78.10324.2FL | C402H22 | 4627 | 3743 | 0 | NO |
| C694 | C402H22 | SCD1U16V2KX-3GP | 78.10421.2FL | C402H22 | 1430 | 7895 | 0 | NO |
| C695 | C402H22 | SCD01U50V2KX-1GP | 78.10324.2FL | C402H22 | 1465 | 7895 | 0 | NO |
| C696 | C603H36 | SC220P50V3JN-GP | 78.22134.1BL | C603H36 | 1570 | 8040 | 270 | NO |
| C697 | C603H36 | SC220P50V3JN-GP | 78.22134.1BL | C603H36 | 1570 | 7830 | 270 | NO |
| C698 | C603H36 | SC220P50V3JN-GP | 78.22134.1BL | C603H36 | 1675 | 7830 | 90 | NO |
| C699 | C603H36 | SC220P50V3JN-GP | 78.22134.1BL | C603H36 | 1675 | 8040 | 90 | NO |
| C700 | C402H22 | SCD1U16V2KX-3GP | 78.10421.2FL | C402H22 | 1502 | 7344 | 0 | NO |
| C701 | C402H22 | SCD01U50V2KX-1GP | 78.10324.2FL | C402H22 | 1537 | 7344 | 0 | NO |
| C702 | C603H36 | SC220P50V3JN-GP | 78.22134.1BL | C603H36 | 1965 | 7805 | 270 | NO |
| C703 | C603H36 | SC220P50V3JN-GP | 78.22134.1BL | C603H36 | 1965 | 7595 | 270 | NO |
| C704 | C603H36 | SC220P50V3JN-GP | 78.22134.1BL | C603H36 | 2070 | 7595 | 90 | NO |
| C705 | C603H36 | SC220P50V3JN-GP | 78.22134.1BL | C603H36 | 2070 | 7805 | 90 | NO |
| C706 | C402H22 | SCD1U16V2KX-3GP | 78.10421.2FL | C402H22 | 1825 | 7660 | 0 | NO |
| C707 | C402H22 | SCD01U50V2KX-1GP | 78.10324.2FL | C402H22 | 1860 | 7660 | 0 | NO |
| C708 | C603H36 | SC220P50V3JN-GP | 78.22134.1BL | C603H36 | 1965 | 7250 | 270 | NO |
| C709 | C603H36 | SC220P50V3JN-GP | 78.22134.1BL | C603H36 | 1965 | 7040 | 270 | NO |
| C710 | C603H36 | SC220P50V3JN-GP | 78.22134.1BL | C603H36 | 2070 | 7040 | 90 | NO |
| C711 | C603H36 | SC220P50V3JN-GP | 78.22134.1BL | C603H36 | 2070 | 7250 | 90 | NO |
| C712 | C402H22 | SCD1U10V2KX-5GP | 78.10423.2FL | C402H22 | 6270 | 3481 | 180 | YES |
| C713 | C402H22 | SCD1U10V2KX-5GP | 78.10423.2FL | C402H22 | 6390 | 3481 | 180 | YES |
| C714 | C402H22 | SCD1U10V2KX-5GP | 78.10423.2FL | C402H22 | 6390 | 3651 | 0 | YES |
| C715 | C402H22 | SCD1U10V2KX-5GP | 78.10423.2FL | C402H22 | 6305 | 3481 | 180 | YES |
| C716 | C402H22 | SCD1U10V2KX-5GP | 78.10423.2FL | C402H22 | 6245 | 3546 | 90 | YES |
| C717 | C402H22 | SCD1U10V2KX-5GP | 78.10423.2FL | C402H22 | 6355 | 3651 | 0 | YES |
| C718 | C402H22 | SCD1U10V2KX-5GP | 78.10423.2FL | C402H22 | 6355 | 3481 | 180 | YES |
| C719 | C402H22 | SC1U10V2KX-4-GP | 78.10523.8FL | C402H22 | 6041.7 | 3323.4 | 180 | NO |
| C720 | C402H22 | SC1U10V2KX-4-GP | 78.10523.8FL | C402H22 | 6415 | 3596 | 270 | YES |
| C721 | C402H22 | SCD1U10V2KX-5GP | 78.10423.2FL | C402H22 | 6415 | 3556 | 270 | YES |
| C723 | C805H54 | SC10U16V5KX-1-GP | 78.10621.81L | C805H54 | 5144.7700000000004 | 2937.4 | 90 | NO |
| C724 | C402H22 | SCD1U10V2KX-5GP | 78.10423.2FL | C402H22 | 5054.7700000000004 | 2937.4 | 180 | NO |
| C727 | C402H22 | SCD1U10V2KX-5GP | 78.10423.2FL | C402H22 | 9065 | 485 | 90 | NO |
| C728 | C402H22 | SCD01U25V2KX-3GP | 78.10322.2FL | C402H22 | 9065 | 450 | 90 | NO |
| C729 | C402H22 | SCD22U10V2KX-1GP | 78.22423.5FL | C402H22 | 8318 | 1797 | 90 | YES |
| C730 | C402H22 | SCD22U10V2KX-1GP | 78.22423.5FL | C402H22 | 8318 | 1762 | 90 | YES |
| C731 | C805H54 | SC10U16V5KX-1-GP | 78.10621.81L | C805H54 | 6248 | 3621 | 90 | YES |
| C1698 | C1206H75 | SC22UF16V6KX-GP | 78.22621.82L | C1206H75 | 4698.8900000000003 | 3242.1 | 270 | NO |
| C3201 | C402H22 | SCD1U25V2KX-2-GP | 78.10422.2FL | C402H22 | 2901.78 | 7344.31 | 0 | YES |
| C3202 | C402H22 | SCD1U25V2KX-2-GP | 78.10422.2FL | C402H22 | 8475 | 7639 | 0 | YES |
| C3203 | C402H22 | SCD1U25V2KX-2-GP | 78.10422.2FL | C402H22 | 8761.48 | 7648.98 | 270 | YES |
| C3204 | C402H22 | SCD1U25V2KX-2-GP | 78.10422.2FL | C402H22 | 13414 | 6919 | 0 | YES |
| C3205 | C402H22 | SCD1U25V2KX-2-GP | 78.10422.2FL | C402H22 | 8926.7800000000007 | 7634.31 | 0 | YES |
| C3206 | C402H22 | SCD1U25V2KX-2-GP | 78.10422.2FL | C402H22 | 13249 | 6919 | 0 | YES |
| C3207 | C402H22 | SCD1U25V2KX-2-GP | 78.10422.2FL | C402H22 | 5351.78 | 7864.31 | 0 | YES |
| C3208 | C402H22 | SCD1U25V2KX-2-GP | 78.10422.2FL | C402H22 | 4804.0600000000004 | 8223.98 | 180 | NO |
| C3209 | C402H22 | SCD1U25V2KX-2-GP | 78.10422.2FL | C402H22 | 4870 | 7864 | 0 | YES |
| C3210 | C402H22 | SCD1U25V2KX-2-GP | 78.10422.2FL | C402H22 | 5031.78 | 7864.31 | 0 | YES |
| C3211 | C402H22 | SCD1U25V2KX-2-GP | 78.10422.2FL | C402H22 | 3221.78 | 7344.31 | 0 | YES |
| C3212 | C402H22 | SCD1U25V2KX-2-GP | 78.10422.2FL | C402H22 | 13781.6 | 1828.01 | 0 | NO |
| C3213 | C402H22 | SCD1U25V2KX-2-GP | 78.10422.2FL | C402H22 | 2735 | 7344 | 0 | YES |
| C3214 | C402H22 | SCD1U25V2KX-2-GP | 78.10422.2FL | C402H22 | 13074 | 6919 | 0 | YES |
| C3215 | C402H22 | SCD1U25V2KX-2-GP | 78.10422.2FL | C402H22 | 8499.06 | 7993.98 | 180 | NO |
| C3216 | C402H22 | SCD1U25V2KX-2-GP | 78.10422.2FL | C402H22 | 1217.99 | 3617.64 | 0 | NO |
| C3217 | C402H22 | SCD1U25V2KX-2-GP | 78.10422.2FL | C402H22 | 985 | 6000 | 0 | NO |
| C3701 | C402H22 | SCD1U25V2KX-2-GP | 78.10422.2FL | C402H22 | 12540 | 3920 | 180 | NO |
| C3702 | C402H22 | SCD047U25V2KX-GP | 78.47322.2FL | C402H22 | 12575 | 3920 | 180 | NO |
| C4104 | C603H36 | SCD1U25V3KX-GP | 78.10422.2BL | C603H36 | 2902 | 7093 | 180 | NO |
| C4108 | C603H36 | SCD1U25V3KX-GP | 78.10422.2BL | C603H36 | 3095 | 7124 | 270 | NO |
| C4112 | C603H36 | SCD1U25V3KX-GP | 78.10422.2BL | C603H36 | 3045 | 7801 | 90 | YES |
| C4116 | C603H36 | SCD1U25V3KX-GP | 78.10422.2BL | C603H36 | 6498 | 7882 | 270 | YES |
| C4120 | C603H36 | SCD1U25V3KX-GP | 78.10422.2BL | C603H36 | 8703.52 | 7414.5 | 90 | NO |
| C4124 | C603H36 | SCD1U25V3KX-GP | 78.10422.2BL | C603H36 | 8866 | 7398 | 90 | NO |
| C4128 | C603H36 | SCD1U25V3KX-GP | 78.10422.2BL | C603H36 | 8881.3700000000008 | 8125.39 | 90 | NO |
| C4132 | C603H36 | SCD1U25V3KX-GP | 78.10422.2BL | C603H36 | 11727 | 8142 | 270 | NO |
| C4136 | C603H36 | SCD1U25V3KX-GP | 78.10422.2BL | C603H36 | 3459 | 7309 | 90 | NO |
| C4140 | C603H36 | SCD1U25V3KX-GP | 78.10422.2BL | C603H36 | 6489 | 8145 | 270 | NO |
| C4144 | C603H36 | SCD1U25V3KX-GP | 78.10422.2BL | C603H36 | 5267 | 8297 | 270 | NO |
| C4148 | C603H36 | SCD1U25V3KX-GP | 78.10422.2BL | C603H36 | 6980 | 8173 | 90 | YES |
| C4152 | C603H36 | SCD1U25V3KX-GP | 78.10422.2BL | C603H36 | 11656.07 | 8230.1 | 90 | YES |
| C4156 | C603H36 | SCD1U25V3KX-GP | 78.10422.2BL | C603H36 | 13018 | 8184 | 270 | NO |
| C4160 | C603H36 | SCD1U25V3KX-GP | 78.10422.2BL | C603H36 | 13267 | 8174 | 90 | YES |
| C7272 | C402H22 | SCD1U16V2KX-3GP | 78.10421.2FL | C402H22 | 473 | 7114 | 0 | NO |
| C7273 | C402H22 | SCD01U16V2KX-3GP | 78.10321.2FL | C402H22 | 429 | 7650 | 180 | NO |
| C7274 | C603H36 | SCD1U25V3KX-GP | 78.10422.2BL | C603H36 | 1303 | 8350 | 90 | NO |
| C7275 | C603H36 | SC1U16V3KX-5GP | 78.10521.2BL | C603H36 | 828 | 7624 | 90 | NO |
| C7276 | C603H36 | SC1U16V3KX-5GP | 78.10521.2BL | C603H36 | 829 | 7493 | 90 | NO |
| C7277 | C603H36 | SC1U16V3KX-5GP | 78.10521.2BL | C603H36 | 649 | 7739 | 180 | NO |
| C7278 | C603H36 | SCD1U25V3JX-GP | 78.10432.2BL | C603H36 | 555 | 7753 | 270 | NO |
| C7279 | C603H36 | SCD033U50V3KX-1GP | 78.33324.2BL | C603H36 | 1257 | 7613 | 90 | NO |
| C7316 | C603H36 | SCD1U25V3JX-GP | 78.10432.2BL | C603H36 | 698 | 7659 | 180 | NO |
| C7317 | C603H36 | SCD1U25V3JX-GP | 78.10432.2BL | C603H36 | 478 | 7664 | 180 | NO |
| C8081 | C402H22 | SCD1U25V2KX-2-GP | 78.10422.2FL | C402H22 | 2170 | 5365 | 180 | YES |
| C8083 | C402H22 | SCD1U25V2KX-2-GP | 78.10422.2FL | C402H22 | 2465 | 5275 | 0 | NO |
| C8084 | C402H22 | SCD1U25V2KX-2-GP | 78.10422.2FL | C402H22 | 2465 | 5195 | 180 | NO |
| C8085 | C402H22 | SCD1U25V2KX-2-GP | 78.10422.2FL | C402H22 | 2210 | 5275 | 180 | NO |
| C8086 | C402H22 | SCD1U25V2KX-2-GP | 78.10422.2FL | C402H22 | 2210 | 5200 | 0 | NO |
| C8087 | C402H22 | SCD1U25V2KX-2-GP | 78.10422.2FL | C402H22 | 2210 | 5200 | 0 | YES |
| C8088 | C402H22 | SCD1U25V2KX-2-GP | 78.10422.2FL | C402H22 | 2210 | 5275 | 180 | YES |
| C8089 | C402H22 | SCD1U25V2KX-2-GP | 78.10422.2FL | C402H22 | 3175 | 5345 | 90 | NO |
| C8091 | C402H22 | SCD047U25V2KX-GP | 78.47322.2FL | C402H22 | 2710 | 7590 | 90 | YES |
| C8092 | C402H22 | SCD047U25V2KX-GP | 78.47322.2FL | C402H22 | 8486.6 | 7874.9 | 180 | YES |
| C8093 | C402H22 | SCD047U25V2KX-GP | 78.47322.2FL | C402H22 | 13060 | 7150 | 0 | YES |
| C8094 | C402H22 | SCD047U25V2KX-GP | 78.47322.2FL | C402H22 | 4885 | 8100 | 0 | YES |
| C8099 | C402H22 | SC1KP50V2KX-1GP | 78.10224.2FL | C402H22 | 775 | 7193 | 90 | NO |
| CA1 | C805H54 | SC2D2U25V5KX-2-GP | 78.22522.21L | C805H54 | 373 | 7084 | 0 | NO |
| CN2 | 232-97-12GBE8 | PIN-CONN24A-4-GP | 021.D0078.0212 | 232-97-12GBE8 | 2429.4699999999998 | 910.89 | 90 | NO |
| CN3 | A2005WR0-2CX7P-6T | JWT-CONN14A-1-GP | 21.63105.207 | A2005WR0-2CX7P-6T | 9352.36 | 98.43 | 180 | NO |
| CN5 | 87332-1420-1 | MLX-CONN14A-16-GP | 021.D0221.0207 | 87332-1420-1 | 5459 | 1840 | 0 | NO |
| CN7 | HBA1030-H300R-EF | FOX-CON2-S23-GP | 020.60030.0102 | HBA1030-H300R-EF | 8192.91 | 2753.54 | 270 | NO |
| CN9 | HBA1030-H300R-EF | FOX-CON2-S23-GP | 020.60030.0102 | HBA1030-H300R-EF | 10751.97 | 1021.26 | 90 | NO |
| CN11 | 91932-31111LF | FCI-CONN11-2-GP | 020.F0528.0011 | 91932-31111LF | 1048.9000000000001 | 2480.31 | 0 | NO |
| CN15 | PREFIT-144P-459383U2H519 | MLX-CONN144-12R-3-GP-U2 | 020.80445.0001 | PREFIT-144P-459383U2H519 | 6009.23 | 375.2 | 0 | NO |
| CN16 | PREFIT-144P-459383U2H519 | MLX-CONN144-12R-3-GP-U2 | 020.80445.0001 | PREFIT-144P-459383U2H519 | 12032.85 | 375.2 | 0 | NO |
| D11 | L1608-UH15 | PGB1010603MR-GP | 69.10059.031 | L1608-UH15 | 344 | 2049 | 270 | NO |
| D12 | L1608-UH15 | PGB1010603MR-GP | 69.10059.031 | L1608-UH15 | 497.5 | 2001 | 270 | NO |
| D13 | SOT23-2D4-312H48 | BAT54C-7-F-3-GP | 75.00054.E7D | SOT23-2D4-312H48 | 4824.6899999999996 | 3120.83 | 270 | NO |
| D14 | L1608-UH15 | PGB1010603MR-GP | 69.10059.031 | L1608-UH15 | 449 | 2049 | 90 | NO |
| D15 | L1608-UH15 | PGB1010603MR-GP | 69.10059.031 | L1608-UH15 | 602.5 | 2001 | 90 | NO |
| D16 | L1608-UH15 | PGB1010603MR-GP | 69.10059.031 | L1608-UH15 | 706 | 2048 | 270 | NO |
| D17 | L1608-UH15 | PGB1010603MR-GP | 69.10059.031 | L1608-UH15 | 851.5 | 1994 | 270 | NO |
| D18 | L1608-UH15 | PGB1010603MR-GP | 69.10059.031 | L1608-UH15 | 811 | 2048 | 90 | NO |
| D19 | L1608-UH15 | PGB1010603MR-GP | 69.10059.031 | L1608-UH15 | 956.5 | 1994 | 90 | NO |
| D36 | SOD323AKH44 | MM3Z15VT1G-GP-U | 83.15R03.B3F | SOD323AKH44 | 1240 | 7685 | 90 | NO |
| D37 | SOD123AK-2H43 | SMF15A-GP | 83.SMF15.0AH | SOD123AK-2H43 | 1284 | 8270 | 270 | NO |
| D1401 | SOD323AKH38 | RB551V30-GP | 83.R5003.H8H | SOD323AKH38 | 785 | 6200 | 180 | NO |
| D1402 | SOD323AKH38 | RB551V30-GP | 83.R5003.H8H | SOD323AKH38 | 700 | 6200 | 180 | NO |
| D1403 | SOD323AKH38 | RB551V30-GP | 83.R5003.H8H | SOD323AKH38 | 295 | 5270.62 | 270 | NO |
| D1404 | SOD323AKH42 | BAT54WS-7-F-GP | 83.R2003.K8F | SOD323AKH42 | 595.5 | 3625.33 | 0 | NO |
| F1 | POLYSW-3217-UH40 | POLYSW-1D5A8V-4-GP | 69.50007.D21 | POLYSW-3217-UH40 | 1390 | 2240 | 180 | NO |
| G1 | TPAD-JTAG-7P | TPAD-JTAG-7P-GP | ZZ.0TPAD.001 | TPAD-JTAG-7P | 2355 | 4690 | 0 | NO |
| GF8 | GF-200P-8-U1 | GF-200P-8-GP-U1 | ZZ.GF001.H81 | GF-200P-8-U1 | 2964.57 | 8925.2000000000007 | 180 | NO |
| GF9 | GF-200P-8-U1 | GF-200P-8-GP-U1 | ZZ.GF001.H81 | GF-200P-8-U1 | 7137.8 | 8925.2000000000007 | 180 | NO |
| GF10 | GF-200P-8-U1 | GF-200P-8-GP-U1 | ZZ.GF001.H81 | GF-200P-8-U1 | 12098.43 | 8925.2000000000007 | 180 | NO |
| JP1 | 21S-91-03GB01 | PIN-CON3-S-GP | 21.61445.103 | 21S-91-03GB01 | 3362 | 2072 | 180 | NO |
| JP4 | 21S-91-03GB01 | PIN-CON3-S-GP | 21.61445.103 | 21S-91-03GB01 | 4884.62 | 1907.61 | 270 | NO |
| JP6 | 21S-91-03GB01 | PIN-CON3-S-GP | 21.61445.103 | 21S-91-03GB01 | 4654.8500000000004 | 1906.8 | 90 | NO |
| JP10 | 21S-91-03GB01 | PIN-CON3-S-GP | 21.61445.103 | 21S-91-03GB01 | 7953 | 161 | 180 | NO |
| JP12 | 21S-91-03GB01 | PIN-CON3-S-GP | 21.61445.103 | 21S-91-03GB01 | 7623 | 162 | 0 | NO |
| JP13 | 21S-91-03GB01 | PIN-CON3-S-GP | 21.61445.103 | 21S-91-03GB01 | 3025 | 2072 | 0 | NO |
| L1 | L7066-1830-UH119 | IND-10UH-147-GP-U | 68.10010.20I | L7066-1830-UH119 | 9494 | 441 | 270 | NO |
| L2 | L101100H158 | IND-10UH-103-GP | 68.1001A.10A | L101100H158 | 7196.89 | 2126.1799999999998 | 90 | NO |
| L4 | L805H42 | MMZ2012S601ATA1N-GP | 68.00109.171 | L805H42 | 2350 | 5095 | 270 | NO |
| L5 | L805H42 | MMZ2012S601ATA1N-GP | 68.00109.171 | L805H42 | 640 | 5725 | 90 | NO |
| L6 | L805H42 | MMZ2012S601ATA1N-GP | 68.00109.171 | L805H42 | 640 | 5645 | 90 | NO |
| L7 | L20125H42 | BLM21PG300SN-2GP | 68.00084.A61 | L20125H42 | 1468 | 2661 | 270 | NO |
| L8 | L2012-4P-1MH40 | DLW21HN900SQ2LGP-U | 68.00201.141 | L2012-4P-1MH40 | 1707.84 | 1841.86 | 0 | NO |
| L10 | L603H26 | BLM18SG121TN1D-GP | 68.00143.221 | L603H26 | 6128.3 | 3386.5 | 180 | NO |
| LED4 | LED3020-1A2K-1H44 | LED-R-126-GP-U2 | 83.1221R.070 | LED3020-1A2K-1H44 | 7700.79 | 0 | 90 | NO |
| LED5 | LED3020AK-U2H44 | LED-B-77-GP-U3 | 83.01221.I70 | LED3020AK-U2H44 | 8094.49 | 0 | 90 | NO |
| LED8 | LED1608AKH40 | LED-YG-51-GP | 83.01921.S70 | LED1608AKH40 | 4944.88 | 787.4 | 90 | NO |
| LED9 | LED1608AKH40 | LED-YG-51-GP | 83.01921.S70 | LED1608AKH40 | 4944.88 | 551.17999999999995 | 90 | NO |
| LED10 | LED1608AKH40 | LED-YG-51-GP | 83.01921.S70 | LED1608AKH40 | 4944.88 | 314.95999999999998 | 90 | NO |
| LED11 | LED1608AKH40 | LED-YG-51-GP | 83.01921.S70 | LED1608AKH40 | 4944.88 | 78.739999999999995 | 90 | NO |
| LED12 | LED1608AKH40 | LED-YG-51-GP | 83.01921.S70 | LED1608AKH40 | 12996.06 | 787.4 | 270 | NO |
| LED13 | LED1608AKH40 | LED-YG-51-GP | 83.01921.S70 | LED1608AKH40 | 12996.06 | 551.17999999999995 | 270 | NO |
| LED14 | 19-21UBC-1 | LED-Y-11-GP | 83.01921.C70 | 19-21UBC-1 | 8925 | 230 | 0 | NO |
| LED15 | LED1608AKH40 | LED-YG-51-GP | 83.01921.S70 | LED1608AKH40 | 12996.06 | 314.95999999999998 | 270 | NO |
| LED16 | LED1608AKH40 | LED-YG-51-GP | 83.01921.S70 | LED1608AKH40 | 12996.06 | 78.739999999999995 | 270 | NO |
| LED18 | LED1608AKH40 | LED-YG-51-GP | 83.01921.S70 | LED1608AKH40 | 7110.24 | 688.98 | 270 | NO |
| LED19 | LED1608AKH40 | LED-YG-51-GP | 83.01921.S70 | LED1608AKH40 | 7307.09 | 688.98 | 270 | NO |
| LED20 | LED1608AKH40 | LED-YG-51-GP | 83.01921.S70 | LED1608AKH40 | 7503.94 | 688.98 | 270 | NO |
| LED21 | LED1608AKH40 | LED-YG-51-GP | 83.01921.S70 | LED1608AKH40 | 10456.69 | 688.98 | 90 | NO |
| LED22 | LED1608AKH40 | LED-YG-51-GP | 83.01921.S70 | LED1608AKH40 | 10653.54 | 688.98 | 90 | NO |
| LED23 | LED1608AKH40 | LED-YG-51-GP | 83.01921.S70 | LED1608AKH40 | 10850.39 | 688.98 | 90 | NO |
| OSC1 | OSC-3225-4P-3H48 | OSC-48MHZ-28-GP | 82.20013.291 | OSC-3225-4P-3H48 | 985 | 5810 | 270 | NO |
| P2121 | 0R0603-PAD-1-U | 0R0603-PAD-2-GP-U | ZZ.00PAD.M21 | 0R0603-PAD-1-U | 625 | 7174 | 90 | NO |
| PAD2 | HT24X28B8R32-3P-S | PAD-3P-GP | ZZ.00PAD.191 | HT24X28B8R32-3P-S | 3364.17 | 212.6 | 0 | NO |
| PAD3 | HT219X276B8R32-3P-S | PAD-3P-GP | ZZ.00PAD.191 | HT219X276B8R32-3P-S | 13769.68 | 212.6 | 0 | NO |
| PAD4 | HT12X22B8R32-2P-S | PAD-2P-21-GP | ZZ.ATPAD.001 | HT12X22B8R32-2P-S | 7898.5 | 2362.1999999999998 | 0 | NO |
| PAD5 | STF256R168H278 | STF256R168H278-GP | 087.71242.0465 | STF256R168H278 | 543.78 | 2374.02 | 90 | NO |
| PC17 | C402H22 | SC820P50V2KX-1GP | 78.82124.2FL | C402H22 | 2433 | 6434 | 270 | NO |
| PC18 | C402H22 | SCD01U25V2KX-3GP | 78.10322.2FL | C402H22 | 2413 | 6374 | 180 | NO |
| PC19 | C805H56 | SC22U6D3V5MX-5-GP | 78.22610.81L | C805H56 | 2578 | 6224 | 90 | NO |
| PC20 | C805H58 | SC10U10V5KX-6-GP-U | 78.10623.21L | C805H58 | 2763 | 6479 | 180 | NO |
| PC21 | C805H56 | SC10U25V5KX-GP | 78.10622.51L | C805H56 | 2525 | 1797.22 | 90 | NO |
| PC22 | C805H56 | SC10U25V5KX-GP | 78.10622.51L | C805H56 | 2525 | 1850 | 90 | YES |
| PC23 | C805H56 | SC10U25V5KX-GP | 78.10622.51L | C805H56 | 2525 | 1770 | 90 | YES |
| PC24 | C805H56 | SC10U25V5KX-GP | 78.10622.51L | C805H56 | 2330 | 1775 | 270 | NO |
| PC25 | C805H56 | SC10U25V5KX-GP | 78.10622.51L | C805H56 | 2525 | 1719.22 | 90 | NO |
| PC26 | C805H58 | SC4D7U25V5KX-1-GP | 078.47522.0211 | C805H58 | 2285 | 1465 | 0 | YES |
| PC27 | C603H36 | SCD1U50V3KX-GP | 78.10424.2BL | C603H36 | 2831 | 1489 | 90 | YES |
| PC28 | C603 | SC2K2P50V3KX-GP | 78.22224.2BL | C603 | 2762 | 1569 | 180 | YES |
| PC29 | C402H22 | SC1U10V2KX-4-GP | 78.10523.8FL | C402H22 | 2396 | 1479 | 180 | NO |
| PC30 | C402H22 | SCD1U25V2KX-2-GP | 78.10422.2FL | C402H22 | 2945 | 1475 | 0 | YES |
| PC31 | C402H22 | SC1KP50V2KX-1GP | 78.10224.2FL | C402H22 | 2795 | 1300 | 270 | NO |
| PC32 | C805H56 | SC10U25V5KX-GP | 78.10622.51L | C805H56 | 2525 | 1877.22 | 90 | NO |
| PC33 | C805H56 | SC10U25V5KX-GP | 78.10622.51L | C805H56 | 2330 | 1690 | 270 | NO |
| PC39 | C805H58 | SC10U6D3V5KX-4GP | 78.10620.21L | C805H58 | 3430 | 1835 | 180 | NO |
| PC40 | C805H58 | SC10U6D3V5KX-4GP | 78.10620.21L | C805H58 | 3350 | 1835 | 180 | NO |
| PC66 | C805H58 | SC22U16V5MX-4-GP | 078.22611.0811 | C805H58 | 1534.21 | 3053.58 | 180 | NO |
| PC68 | C805H58 | SC22U16V5MX-4-GP | 078.22611.0811 | C805H58 | 1614 | 3054 | 180 | NO |
| PC69 | C805H56 | SC4D7U16V5KX-1-GP | 78.47521.21L | C805H56 | 5895 | 3525 | 180 | NO |
| PC70 | C805H56 | SC4D7U16V5KX-1-GP | 78.47521.21L | C805H56 | 2578 | 6064 | 90 | NO |
| PC71 | C603H36 | SCD1U50V3KX-GP | 78.10424.2BL | C603H36 | 1423 | 3064 | 90 | NO |
| PC72 | C805H58 | SC4D7U25V5KX-1-GP | 078.47522.0211 | C805H58 | 1235 | 2774 | 270 | NO |
| PC73 | C603H36 | SC22P50V3JN-GP | 78.22034.1BL | C603H36 | 1236.8 | 3127.14 | 0 | NO |
| PC74 | C402H22 | SCD01U25V2KX-3GP | 78.10322.2FL | C402H22 | 2653 | 6474 | 270 | NO |
| PC75 | C805H56 | SC22U6D3V5MX-5-GP | 78.22610.81L | C805H56 | 2578 | 6144 | 90 | NO |
| PC76 | C402H22 | SC1KP50V2KX-1GP | 78.10224.2FL | C402H22 | 2763 | 6349 | 90 | NO |
| PC77 | C805H56 | SC4D7U16V5KX-1-GP | 78.47521.21L | C805H56 | 695 | 4305 | 90 | NO |
| PC78 | C402H22 | SCD01U25V2KX-3GP | 78.10322.2FL | C402H22 | 685 | 4225 | 0 | NO |
| PC79 | C805H56 | SC22U6D3V5MX-5-GP | 78.22610.81L | C805H56 | 695 | 4385 | 90 | NO |
| PC80 | C805H58 | SC10U6D3V5KX-4GP | 78.10620.21L | C805H58 | 310 | 4200 | 0 | NO |
| PC81 | C805H56 | SC22U6D3V5MX-5-GP | 78.22610.81L | C805H56 | 510 | 4395 | 270 | NO |
| PC82 | C805H56 | SC22U6D3V5MX-5-GP | 78.22610.81L | C805H56 | 315 | 4380 | 180 | NO |
| PC83 | C402H22 | SC1KP50V2KX-1GP | 78.10224.2FL | C402H22 | 430 | 4260 | 90 | YES |
| PC84 | C402H22 | SC820P50V2KX-1GP | 78.82124.2FL | C402H22 | 665 | 4170 | 90 | NO |
| PC85 | C402H22 | SCD01U25V2KX-3GP | 78.10322.2FL | C402H22 | 430 | 4220 | 90 | YES |
| PC86 | C402H22 | SCD01U25V2KX-3GP | 78.10322.2FL | C402H22 | 5565.31 | 3630.8 | 0 | YES |
| PC87 | C402H22 | SCD01U25V2KX-3GP | 78.10322.2FL | C402H22 | 5600.31 | 3389.8 | 270 | NO |
| PC88 | C805H56 | SC22U6D3V5MX-5-GP | 78.22610.81L | C805H56 | 5740 | 3525 | 180 | NO |
| PC89 | C402H22 | SC1KP50V2KX-1GP | 78.10224.2FL | C402H22 | 5605.31 | 3630.8 | 0 | YES |
| PC90 | C805H56 | SC22U6D3V5MX-5-GP | 78.22610.81L | C805H56 | 5817 | 3525 | 180 | NO |
| PC91 | C805H58 | SC10U10V5KX-6-GP-U | 78.10623.21L | C805H58 | 5545.31 | 3750.8 | 270 | NO |
| PC92 | C402H22 | SC820P50V2KX-1GP | 78.82124.2FL | C402H22 | 5544 | 3411 | 0 | NO |
| PC93 | C805H56 | SC22U6D3V5MX-5-GP | 78.22610.81L | C805H56 | 5730 | 3750 | 90 | NO |
| PC94 | C805H56 | SC4D7U16V5KX-1-GP | 78.47521.21L | C805H56 | 6602.63 | 2326.08 | 0 | NO |
| PC95 | C805H56 | SC22U6D3V5MX-5-GP | 78.22610.81L | C805H56 | 2763 | 6254 | 0 | NO |
| PC96 | C805H56 | SC4D7U16V5KX-1-GP | 78.47521.21L | C805H56 | 12605 | 2700 | 180 | YES |
| PC169 | C805H56 | SC10U25V5KX-GP | 78.10622.51L | C805H56 | 13634.81 | 2405.09 | 90 | NO |
| PC170 | C805H56 | SC10U25V5KX-GP | 78.10622.51L | C805H56 | 13425 | 2400 | 270 | YES |
| PC172 | C603H36 | SCD1U50V3KX-GP | 78.10424.2BL | C603H36 | 13440 | 2465 | 270 | NO |
| PC173 | C805H56 | SC10U25V5KX-GP | 78.10622.51L | C805H56 | 13635.4 | 2481.21 | 90 | NO |
| PC174 | C805H56 | SC10U25V5KX-GP | 78.10622.51L | C805H56 | 13425 | 2480 | 270 | YES |
| PC175 | C805H56 | SC10U25V5KX-GP | 78.10622.51L | C805H56 | 13425 | 2400 | 270 | NO |
| PC176 | C805H56 | SC22U6D3V5MX-5-GP | 78.22610.81L | C805H56 | 12585 | 2180 | 0 | YES |
| PC177 | C805H56 | SC22U6D3V5MX-5-GP | 78.22610.81L | C805H56 | 12500 | 2180 | 0 | YES |
| PC178 | C805H56 | SC22U6D3V5MX-5-GP | 78.22610.81L | C805H56 | 12340 | 2180 | 0 | YES |
| PC179 | C805H56 | SC22U6D3V5MX-5-GP | 78.22610.81L | C805H56 | 12445 | 2700 | 180 | YES |
| PC180 | C805H56 | SC22U6D3V5MX-5-GP | 78.22610.81L | C805H56 | 12285 | 2700 | 180 | YES |
| PC181 | C805H56 | SC22U6D3V5MX-5-GP | 78.22610.81L | C805H56 | 12525 | 2700 | 180 | YES |
| PC182 | C805H56 | SC22U6D3V5MX-5-GP | 78.22610.81L | C805H56 | 12365 | 2700 | 180 | YES |
| PC183 | C805H56 | SC22U6D3V5MX-5-GP | 78.22610.81L | C805H56 | 12420 | 2180 | 0 | YES |
| PC184 | C805H58 | SC4D7U25V5KX-1-GP | 078.47522.0211 | C805H58 | 13635 | 2640 | 180 | YES |
| PC185 | C603H36 | SCD1U50V3KX-GP | 78.10424.2BL | C603H36 | 13159 | 2665 | 270 | YES |
| PC186 | C402H22 | SCD1U16V2KX-3GP | 78.10421.2FL | C402H22 | 12895 | 2760 | 180 | YES |
| PC187 | C402H22 | SC1U10V2KX-1GP | 78.10523.5FL | C402H22 | 13190 | 2805 | 0 | NO |
| PC188 | C402H22 | SC470P50V2KX-3GP | 78.47124.2FL | C402H22 | 13260 | 2500 | 90 | YES |
| PC189 | C402H22 | SC1KP50V2KX-1GP | 78.10224.2FL | C402H22 | 13190 | 2865 | 90 | NO |
| PC190 | C603H36 | SC1U16V3KX-5GP | 78.10521.2BL | C603H36 | 13570 | 2685 | 180 | NO |
| PC191 | C603H36 | SCD1U50V3KX-GP | 78.10424.2BL | C603H36 | 5973.63 | 2576.08 | 90 | NO |
| PC192 | C805H56 | SC10U25V5KX-GP | 78.10622.51L | C805H56 | 5988.63 | 2641.08 | 90 | NO |
| PC193 | C603H36 | SC1U16V3KX-5GP | 78.10521.2BL | C603H36 | 5801.78 | 2359.69 | 0 | NO |
| PC194 | C805H56 | SC22U6D3V5MX-5-GP | 78.22610.81L | C805H56 | 6851.63 | 2469.08 | 0 | YES |
| PC195 | C805H56 | SC10U25V5KX-GP | 78.10622.51L | C805H56 | 5965.63 | 2566.08 | 90 | YES |
| PC196 | C1206-TO0D3H75 | SC22U25V6KX-GP-U | 078.22622.082N | C1206-TO0D3H75 | 5715.63 | 2886.08 | 270 | NO |
| PC197 | C805H56 | SC10U25V5KX-GP | 78.10622.51L | C805H56 | 5738.63 | 2536.08 | 270 | YES |
| PC198 | C805H56 | SC10U25V5KX-GP | 78.10622.51L | C805H56 | 5738.63 | 2536.08 | 270 | NO |
| PC199 | C1206-TO0D3H75 | SC22U25V6KX-GP-U | 078.22622.082N | C1206-TO0D3H75 | 5715.63 | 2763.08 | 270 | NO |
| PC200 | C603H36 | SCD1U50V3KX-GP | 78.10424.2BL | C603H36 | 6240.63 | 2331.08 | 90 | YES |
| PC201 | C1206-TO0D3H75 | SC22U25V6KX-GP-U | 078.22622.082N | C1206-TO0D3H75 | 5715.63 | 2640.08 | 270 | NO |
| PC202 | C805H56 | SC22U6D3V5MX-5-GP | 78.22610.81L | C805H56 | 6771.63 | 2469.08 | 0 | YES |
| PC203 | C402H22 | SC1KP50V2KX-1GP | 78.10224.2FL | C402H22 | 6213.63 | 2216.08 | 270 | NO |
| PC204 | C402H22 | SC1U10V2KX-1GP | 78.10523.5FL | C402H22 | 6193.63 | 2301.08 | 180 | NO |
| PC205 | C805H56 | SC22U6D3V5MX-5-GP | 78.22610.81L | C805H56 | 6931.63 | 2469.08 | 0 | YES |
| PC206 | C805H56 | SC10U25V5KX-GP | 78.10622.51L | C805H56 | 5738.63 | 2456.08 | 270 | NO |
| PC207 | C402H22 | SC470P50V2KX-3GP | 78.47124.2FL | C402H22 | 6140.63 | 2531.08 | 270 | YES |
| PC208 | C402H22 | SCD1U16V2KX-3GP | 78.10421.2FL | C402H22 | 6456.63 | 2365.08 | 0 | YES |
| PC209 | C805H56 | SC22U6D3V5MX-5-GP | 78.22610.81L | C805H56 | 6691.63 | 2469.08 | 0 | YES |
| PC210 | C1206-TO0D3H75 | SC22U25V6KX-GP-U | 078.22622.082N | C1206-TO0D3H75 | 5965.63 | 2744.08 | 90 | NO |
| PC211 | C1206-TO0D3H75 | SC22U25V6KX-GP-U | 078.22622.082N | C1206-TO0D3H75 | 5965.63 | 2867.08 | 90 | NO |
| PC212 | C805H58 | SC4D7U25V5KX-1-GP | 078.47522.0211 | C805H58 | 5823.63 | 2336.08 | 0 | YES |
| PC213 | C1206-TO0D3H75 | SC22U25V6KX-GP-U | 078.22622.082N | C1206-TO0D3H75 | 5965.63 | 2990.08 | 90 | NO |
| PC214 | C1206-TO0D3H75 | SC22U25V6KX-GP-U | 078.22622.082N | C1206-TO0D3H75 | 5715.63 | 3009.08 | 270 | NO |
| PC215 | C1206-TO0D3H75 | SC22U25V6KX-GP-U | 078.22622.082N | C1206-TO0D3H75 | 13395 | 1925 | 270 | NO |
| PC216 | C1206-TO0D3H75 | SC22U25V6KX-GP-U | 078.22622.082N | C1206-TO0D3H75 | 13395 | 2050 | 270 | NO |
| PC217 | C1206-TO0D3H75 | SC22U25V6KX-GP-U | 078.22622.082N | C1206-TO0D3H75 | 13640 | 2035 | 90 | NO |
| PC218 | C1206-TO0D3H75 | SC22U25V6KX-GP-U | 078.22622.082N | C1206-TO0D3H75 | 13395 | 2300 | 270 | NO |
| PC219 | C1206-TO0D3H75 | SC22U25V6KX-GP-U | 078.22622.082N | C1206-TO0D3H75 | 13640 | 2170 | 90 | NO |
| PC220 | C1206-TO0D3H75 | SC22U25V6KX-GP-U | 078.22622.082N | C1206-TO0D3H75 | 13640 | 2305 | 90 | NO |
| PC221 | C1206-TO0D3H75 | SC22U25V6KX-GP-U | 078.22622.082N | C1206-TO0D3H75 | 13395 | 2175 | 270 | NO |
| PC222 | C603H36 | SC1U16V3KX-5GP | 78.10521.2BL | C603H36 | 10285 | 680 | 180 | NO |
| PC223 | C603H36 | SC1U16V3KX-5GP | 78.10521.2BL | C603H36 | 10395 | 535 | 0 | YES |
| PC224 | C603H36 | SC1U16V3KX-5GP | 78.10521.2BL | C603H36 | 9945.9699999999993 | 558.69000000000005 | 0 | NO |
| PC1083 | C603H36 | SC1U25V3KX-GP | 78.10522.2BL | C603H36 | 828 | 7364 | 90 | NO |
| PG1 | GAP-CLOSE-PWR-3 | GAP-CLOSE-PWR-3-GP | ZZ.CLOSE.001 | GAP-CLOSE-PWR-3 | 1596.62 | 2712.23 | 90 | NO |
| PG2 | GAP-CLOSE-PWR-3 | GAP-CLOSE-PWR-3-GP | ZZ.CLOSE.001 | GAP-CLOSE-PWR-3 | 1556.62 | 2712.23 | 90 | NO |
| PG3 | CON2C-U | COPPER-CLOSE-GP-U | ZZ.CON2C.XXX | CON2C-U | 2595 | 1330 | 180 | NO |
| PG4 | GAP-CLOSE-PWR-3 | GAP-CLOSE-PWR-3-GP | ZZ.CLOSE.001 | GAP-CLOSE-PWR-3 | 3500 | 1810 | 0 | NO |
| PG5 | GAP-CLOSE-PWR-3 | GAP-CLOSE-PWR-3-GP | ZZ.CLOSE.001 | GAP-CLOSE-PWR-3 | 3500 | 1662 | 0 | NO |
| PG6 | GAP-CLOSE-PWR-3 | GAP-CLOSE-PWR-3-GP | ZZ.CLOSE.001 | GAP-CLOSE-PWR-3 | 3500 | 1736 | 0 | NO |
| PG7 | GAP-CLOSE-PWR-3 | GAP-CLOSE-PWR-3-GP | ZZ.CLOSE.001 | GAP-CLOSE-PWR-3 | 3500 | 1699 | 0 | NO |
| PG8 | GAP-CLOSE-PWR-3 | GAP-CLOSE-PWR-3-GP | ZZ.CLOSE.001 | GAP-CLOSE-PWR-3 | 3500 | 1625 | 0 | NO |
| PG9 | GAP-CLOSE-PWR-3 | GAP-CLOSE-PWR-3-GP | ZZ.CLOSE.001 | GAP-CLOSE-PWR-3 | 3500 | 1773 | 0 | NO |
| PG10 | GAP-CLOSE-PWR-3 | GAP-CLOSE-PWR-3-GP | ZZ.CLOSE.001 | GAP-CLOSE-PWR-3 | 5920.31 | 3395.8 | 0 | NO |
| PG11 | GAP-CLOSE-PWR-3 | GAP-CLOSE-PWR-3-GP | ZZ.CLOSE.001 | GAP-CLOSE-PWR-3 | 2453 | 6044 | 180 | NO |
| PG12 | GAP-CLOSE-PWR-3 | GAP-CLOSE-PWR-3-GP | ZZ.CLOSE.001 | GAP-CLOSE-PWR-3 | 560 | 4465 | 90 | NO |
| PG13 | GAP-CLOSE-PWR-3 | GAP-CLOSE-PWR-3-GP | ZZ.CLOSE.001 | GAP-CLOSE-PWR-3 | 7012 | 2635 | 180 | NO |
| PG14 | GAP-CLOSE-PWR-3 | GAP-CLOSE-PWR-3-GP | ZZ.CLOSE.001 | GAP-CLOSE-PWR-3 | 7012 | 2605 | 180 | NO |
| PG15 | GAP-CLOSE-PWR-3 | GAP-CLOSE-PWR-3-GP | ZZ.CLOSE.001 | GAP-CLOSE-PWR-3 | 7012 | 2575 | 180 | NO |
| PG16 | GAP-CLOSE-PWR-3 | GAP-CLOSE-PWR-3-GP | ZZ.CLOSE.001 | GAP-CLOSE-PWR-3 | 7012 | 2545 | 180 | NO |
| PG17 | GAP-CLOSE-PWR-3 | GAP-CLOSE-PWR-3-GP | ZZ.CLOSE.001 | GAP-CLOSE-PWR-3 | 7011 | 2725 | 0 | YES |
| PG18 | GAP-CLOSE-PWR-3 | GAP-CLOSE-PWR-3-GP | ZZ.CLOSE.001 | GAP-CLOSE-PWR-3 | 7011 | 2515 | 0 | YES |
| PG19 | GAP-CLOSE-PWR-3 | GAP-CLOSE-PWR-3-GP | ZZ.CLOSE.001 | GAP-CLOSE-PWR-3 | 7012 | 2725 | 180 | NO |
| PG20 | GAP-CLOSE-PWR-3 | GAP-CLOSE-PWR-3-GP | ZZ.CLOSE.001 | GAP-CLOSE-PWR-3 | 7012 | 2695 | 180 | NO |
| PG21 | GAP-CLOSE-PWR-3 | GAP-CLOSE-PWR-3-GP | ZZ.CLOSE.001 | GAP-CLOSE-PWR-3 | 7012 | 2515 | 180 | NO |
| PG22 | GAP-CLOSE-PWR-3 | GAP-CLOSE-PWR-3-GP | ZZ.CLOSE.001 | GAP-CLOSE-PWR-3 | 7011 | 2575 | 0 | YES |
| PG23 | GAP-CLOSE-PWR-3 | GAP-CLOSE-PWR-3-GP | ZZ.CLOSE.001 | GAP-CLOSE-PWR-3 | 7011 | 2605 | 0 | YES |
| PG24 | GAP-CLOSE-PWR-3 | GAP-CLOSE-PWR-3-GP | ZZ.CLOSE.001 | GAP-CLOSE-PWR-3 | 7011 | 2635 | 0 | YES |
| PG25 | GAP-CLOSE-PWR-3 | GAP-CLOSE-PWR-3-GP | ZZ.CLOSE.001 | GAP-CLOSE-PWR-3 | 7011 | 2665 | 0 | YES |
| PG26 | GAP-CLOSE-PWR-3 | GAP-CLOSE-PWR-3-GP | ZZ.CLOSE.001 | GAP-CLOSE-PWR-3 | 7011 | 2695 | 0 | YES |
| PG27 | GAP-CLOSE-PWR-3 | GAP-CLOSE-PWR-3-GP | ZZ.CLOSE.001 | GAP-CLOSE-PWR-3 | 7011 | 2545 | 0 | YES |
| PG28 | GAP-CLOSE-PWR-3 | GAP-CLOSE-PWR-3-GP | ZZ.CLOSE.001 | GAP-CLOSE-PWR-3 | 7012 | 2665 | 180 | NO |
| PG29 | GAP-CLOSE-PWR-3 | GAP-CLOSE-PWR-3-GP | ZZ.CLOSE.001 | GAP-CLOSE-PWR-3 | 6987.63 | 2798.08 | 90 | YES |
| PG30 | GAP-CLOSE-PWR-3 | GAP-CLOSE-PWR-3-GP | ZZ.CLOSE.001 | GAP-CLOSE-PWR-3 | 6957.63 | 2798.08 | 270 | NO |
| PG31 | GAP-CLOSE-PWR-3 | GAP-CLOSE-PWR-3-GP | ZZ.CLOSE.001 | GAP-CLOSE-PWR-3 | 6927.63 | 2798.08 | 270 | NO |
| PG32 | GAP-CLOSE-PWR-3 | GAP-CLOSE-PWR-3-GP | ZZ.CLOSE.001 | GAP-CLOSE-PWR-3 | 6987.63 | 2798.08 | 270 | NO |
| PG33 | GAP-CLOSE-PWR-3 | GAP-CLOSE-PWR-3-GP | ZZ.CLOSE.001 | GAP-CLOSE-PWR-3 | 5758 | 3299 | 270 | NO |
| PG34 | GAP-CLOSE-PWR-3 | GAP-CLOSE-PWR-3-GP | ZZ.CLOSE.001 | GAP-CLOSE-PWR-3 | 6927.63 | 2798.08 | 90 | YES |
| PG35 | GAP-CLOSE-PWR-3 | GAP-CLOSE-PWR-3-GP | ZZ.CLOSE.001 | GAP-CLOSE-PWR-3 | 6957.63 | 2798.08 | 90 | YES |
| PG36 | GAP-CLOSE-PWR-3 | GAP-CLOSE-PWR-3-GP | ZZ.CLOSE.001 | GAP-CLOSE-PWR-3 | 12205 | 2545 | 180 | YES |
| PG37 | GAP-CLOSE-PWR-3 | GAP-CLOSE-PWR-3-GP | ZZ.CLOSE.001 | GAP-CLOSE-PWR-3 | 12205 | 2639 | 0 | NO |
| PG38 | GAP-CLOSE-PWR-3 | GAP-CLOSE-PWR-3-GP | ZZ.CLOSE.001 | GAP-CLOSE-PWR-3 | 12205 | 2245 | 180 | YES |
| PG39 | GAP-CLOSE-PWR-3 | GAP-CLOSE-PWR-3-GP | ZZ.CLOSE.001 | GAP-CLOSE-PWR-3 | 12205 | 2275 | 180 | YES |
| PG40 | GAP-CLOSE-PWR-3 | GAP-CLOSE-PWR-3-GP | ZZ.CLOSE.001 | GAP-CLOSE-PWR-3 | 12205 | 2305 | 180 | YES |
| PG41 | GAP-CLOSE-PWR-3 | GAP-CLOSE-PWR-3-GP | ZZ.CLOSE.001 | GAP-CLOSE-PWR-3 | 12205 | 2335 | 180 | YES |
| PG42 | GAP-CLOSE-PWR-3 | GAP-CLOSE-PWR-3-GP | ZZ.CLOSE.001 | GAP-CLOSE-PWR-3 | 12205 | 2609 | 0 | NO |
| PG43 | GAP-CLOSE-PWR-3 | GAP-CLOSE-PWR-3-GP | ZZ.CLOSE.001 | GAP-CLOSE-PWR-3 | 12205 | 2579 | 0 | NO |
| PG44 | GAP-CLOSE-PWR-3 | GAP-CLOSE-PWR-3-GP | ZZ.CLOSE.001 | GAP-CLOSE-PWR-3 | 12205 | 2459 | 0 | NO |
| PG45 | GAP-CLOSE-PWR-3 | GAP-CLOSE-PWR-3-GP | ZZ.CLOSE.001 | GAP-CLOSE-PWR-3 | 12205 | 2429 | 0 | NO |
| PG46 | GAP-CLOSE-PWR-3 | GAP-CLOSE-PWR-3-GP | ZZ.CLOSE.001 | GAP-CLOSE-PWR-3 | 12205 | 2279 | 0 | NO |
| PG47 | GAP-CLOSE-PWR-3 | GAP-CLOSE-PWR-3-GP | ZZ.CLOSE.001 | GAP-CLOSE-PWR-3 | 12205 | 2309 | 0 | NO |
| PG48 | GAP-CLOSE-PWR-3 | GAP-CLOSE-PWR-3-GP | ZZ.CLOSE.001 | GAP-CLOSE-PWR-3 | 12205 | 2339 | 0 | NO |
| PG49 | GAP-CLOSE-PWR-3 | GAP-CLOSE-PWR-3-GP | ZZ.CLOSE.001 | GAP-CLOSE-PWR-3 | 12205 | 2369 | 0 | NO |
| PG50 | GAP-CLOSE-PWR-3 | GAP-CLOSE-PWR-3-GP | ZZ.CLOSE.001 | GAP-CLOSE-PWR-3 | 12205 | 2489 | 0 | NO |
| PG51 | GAP-CLOSE-PWR-3 | GAP-CLOSE-PWR-3-GP | ZZ.CLOSE.001 | GAP-CLOSE-PWR-3 | 12205 | 2519 | 0 | NO |
| PG52 | GAP-CLOSE-PWR-3 | GAP-CLOSE-PWR-3-GP | ZZ.CLOSE.001 | GAP-CLOSE-PWR-3 | 12205 | 2515 | 180 | YES |
| PG53 | GAP-CLOSE-PWR-3 | GAP-CLOSE-PWR-3-GP | ZZ.CLOSE.001 | GAP-CLOSE-PWR-3 | 12205 | 2485 | 180 | YES |
| PG54 | GAP-CLOSE-PWR-3 | GAP-CLOSE-PWR-3-GP | ZZ.CLOSE.001 | GAP-CLOSE-PWR-3 | 12205 | 2455 | 180 | YES |
| PG55 | GAP-CLOSE-PWR-3 | GAP-CLOSE-PWR-3-GP | ZZ.CLOSE.001 | GAP-CLOSE-PWR-3 | 12205 | 2699 | 0 | NO |
| PG56 | GAP-CLOSE-PWR-3 | GAP-CLOSE-PWR-3-GP | ZZ.CLOSE.001 | GAP-CLOSE-PWR-3 | 12205 | 2635 | 180 | YES |
| PG57 | GAP-CLOSE-PWR-3 | GAP-CLOSE-PWR-3-GP | ZZ.CLOSE.001 | GAP-CLOSE-PWR-3 | 12205 | 2549 | 0 | NO |
| PG58 | GAP-CLOSE-PWR-3 | GAP-CLOSE-PWR-3-GP | ZZ.CLOSE.001 | GAP-CLOSE-PWR-3 | 12205 | 2365 | 180 | YES |
| PG59 | GAP-CLOSE-PWR-3 | GAP-CLOSE-PWR-3-GP | ZZ.CLOSE.001 | GAP-CLOSE-PWR-3 | 12205 | 2399 | 0 | NO |
| PG60 | GAP-CLOSE-PWR-3 | GAP-CLOSE-PWR-3-GP | ZZ.CLOSE.001 | GAP-CLOSE-PWR-3 | 12205 | 2249 | 0 | NO |
| PG61 | GAP-CLOSE-PWR-3 | GAP-CLOSE-PWR-3-GP | ZZ.CLOSE.001 | GAP-CLOSE-PWR-3 | 12205 | 2215 | 180 | YES |
| PG62 | GAP-CLOSE-PWR-3 | GAP-CLOSE-PWR-3-GP | ZZ.CLOSE.001 | GAP-CLOSE-PWR-3 | 12205 | 2425 | 180 | YES |
| PG63 | GAP-CLOSE-PWR-3 | GAP-CLOSE-PWR-3-GP | ZZ.CLOSE.001 | GAP-CLOSE-PWR-3 | 12205 | 2395 | 180 | YES |
| PG64 | GAP-CLOSE-PWR-3 | GAP-CLOSE-PWR-3-GP | ZZ.CLOSE.001 | GAP-CLOSE-PWR-3 | 12205 | 2665 | 180 | YES |
| PG65 | GAP-CLOSE-PWR-3 | GAP-CLOSE-PWR-3-GP | ZZ.CLOSE.001 | GAP-CLOSE-PWR-3 | 12205 | 2669 | 0 | NO |
| PG66 | GAP-CLOSE-PWR-3 | GAP-CLOSE-PWR-3-GP | ZZ.CLOSE.001 | GAP-CLOSE-PWR-3 | 12205 | 2575 | 180 | YES |
| PG67 | GAP-CLOSE-PWR-3 | GAP-CLOSE-PWR-3-GP | ZZ.CLOSE.001 | GAP-CLOSE-PWR-3 | 12205 | 2605 | 180 | YES |
| PG68 | GAP-CLOSE-PWR-3 | GAP-CLOSE-PWR-3-GP | ZZ.CLOSE.001 | GAP-CLOSE-PWR-3 | 2453 | 6074 | 180 | NO |
| PG69 | GAP-CLOSE-PWR-3 | GAP-CLOSE-PWR-3-GP | ZZ.CLOSE.001 | GAP-CLOSE-PWR-3 | 590 | 4465 | 90 | NO |
| PG70 | GAP-CLOSE-PWR-3 | GAP-CLOSE-PWR-3-GP | ZZ.CLOSE.001 | GAP-CLOSE-PWR-3 | 5788 | 3299 | 270 | NO |
| PL1 | L47474716H158 | IND-15UH-87-GP | 68.1501A.10Z | L47474716H158 | 1472.19 | 2861.83 | 90 | NO |
| PL2 | L20125H42 | BLM21PG220SN1DGP | 68.00084.831 | L20125H42 | 2330 | 1860 | 90 | NO |
| PL3 | L7066-1830-UH119 | COIL-1D5UH-32-GP | 68.1R51B.10C | L7066-1830-UH119 | 2920 | 1665 | 90 | NO |
| PL8 | L451616H71 | BLM41PG600-GP | 68.00084.771 | L451616H71 | 13610 | 1920 | 180 | NO |
| PL9 | L127126-508254H315 | IND-320NH-4-GP | 68.3212N.10B | L127126-508254H315 | 12940 | 2435 | 270 | NO |
| PL10 | L451616H71 | BLM41PG600-GP | 68.00084.771 | L451616H71 | 5668.59 | 3122.41 | 0 | NO |
| PL11 | L102078-254224H296 | IND-300NH-8-GP | 68.3012N.10C | L102078-254224H296 | 6407.63 | 2576.08 | 90 | NO |
| PQ19 | SOT23DGS2D8H50 | AO3400-GP-U | 84.03400.037 | SOT23DGS2D8H50 | 6028.08 | 2095.37 | 0 | NO |
| PQ20 | SOT23DGS2D8H50 | AO3400-GP-U | 84.03400.037 | SOT23DGS2D8H50 | 13027 | 2967 | 270 | NO |
| PQ21 | SOT23DGS2D8H50 | AO3400-GP-U | 84.03400.037 | SOT23DGS2D8H50 | 10243.299999999999 | 306.32 | 180 | NO |
| PQ22 | SOT23DGS2D8H50 | AO3400-GP-U | 84.03400.037 | SOT23DGS2D8H50 | 8835 | 405 | 180 | YES |
| PQ33 | SOT883CBE1D0-2U1H22 | MMBT3904FN3-GP-U | 084.03904.0013 | SOT883CBE1D0-2U1H22 | 853 | 7214 | 90 | NO |
| PR1 | R402H16 | 13K3R2F-L1-GP | 64.13325.6DL | R402H16 | 1341.8 | 3112.14 | 90 | NO |
| PR2 | R402H16 | 121KR2F-L-GP | 64.12135.6DL | R402H16 | 13550 | 2815 | 180 | YES |
| PR3 | R402H16 | 82KR2J-GP | 63.82334.1DL | R402H16 | 5883.63 | 2226.08 | 0 | YES |
| PR17 | R402H16 | 0R2J-2-GP | 63.R0034.1DL | R402H16 | 2838 | 6439 | 270 | NO |
| PR18 | R402H16 | 1K4R2F-1-GP | 64.14015.6DL | R402H16 | 2815 | 1355 | 180 | NO |
| PR19 | R603H22 | 2D2R3J-2-GP | 63.2R233.15L | R603H22 | 2285 | 1590 | 180 | YES |
| PR20 | R603H22 | 0R3J-0-U-GP | 63.00000.00L | R603H22 | 2795 | 1433 | 270 | YES |
| PR21 | R603H22 | 0R3J-0-U-GP | 63.00000.00L | R603H22 | 13095 | 2714 | 90 | YES |
| PR22 | R603H22 | 0R3J-0-U-GP | 63.00000.00L | R603H22 | 2638 | 6519 | 90 | NO |
| PR23 | R603H22 | 0R3J-0-U-GP | 63.00000.00L | R603H22 | 2857 | 6302 | 270 | NO |
| PR24 | R402H16 | 2K7R2J-GP | 63.27234.1DL | R402H16 | 2775 | 1355 | 0 | NO |
| PR25 | R402H16 | 10KR2F-2-GP | 64.10025.6DL | R402H16 | 2795 | 1455 | 90 | NO |
| PR26 | R402H16 | 2KR2F-3-GP | 64.20015.6DL | R402H16 | 2905 | 1475 | 0 | YES |
| PR27 | R603H22 | 10R3F-GP | 64.10R05.55L | R603H22 | 2890 | 1260 | 270 | NO |
| PR28 | R805H24 | 3D01R5F-GP | 64.3R015.16L | R805H24 | 2715 | 1660 | 270 | YES |
| PR29 | R402H16 | 475KR2F-GP | 64.47535.6DL | R402H16 | 2380 | 1395 | 270 | NO |
| PR30 | R402H16 | 100KR2F-L1-GP | 64.10035.6DL | R402H16 | 2375 | 1340 | 180 | YES |
| PR31 | R402H16 | 121KR2F-L-GP | 64.12135.6DL | R402H16 | 2415 | 1340 | 180 | YES |
| PR32 | R402H16 | 866KR2F-GP | 64.86635.6DL | R402H16 | 2355.0500000000002 | 1463.62 | 0 | NO |
| PR33 | R402H16 | 44K2R2F-1-GP | 64.44225.6DL | R402H16 | 2795 | 1260 | 90 | NO |
| PR34 | R402H16 | 10KR2F-2-GP | 64.10025.6DL | R402H16 | 1042 | 6819 | 270 | NO |
| PR35 | R402H16 | 619KR2F-GP | 64.61935.6DL | R402H16 | 2455 | 1340 | 180 | YES |
| PR36 | R402H16 | 0R2J-2-GP | 63.R0034.1DL | R402H16 | 2870.4 | 1493.5 | 90 | NO |
| PR37 | R402H16 | 10KR2F-2-GP | 64.10025.6DL | R402H16 | 2715 | 1260 | 270 | NO |
| PR38 | R402H16 | 10KR2F-2-GP | 64.10025.6DL | R402H16 | 816 | 6819 | 90 | NO |
| PR39 | R402H16 | 10KR2F-2-GP | 64.10025.6DL | R402H16 | 572 | 6923 | 0 | NO |
| PR43 | R402H16 | 10KR2F-2-GP | 64.10025.6DL | R402H16 | 2763 | 6389 | 270 | NO |
| PR62 | R402H16 | 4K42R2F-GP | 64.44215.6DL | R402H16 | 2373 | 6374 | 180 | NO |
| PR63 | R603H22 | 0R3J-0-U-GP | 63.00000.00L | R603H22 | 1318 | 3064 | 90 | NO |
| PR64 | R402H16 | 47KR2F-GP | 64.47025.6DL | R402H16 | 1161 | 2881 | 270 | YES |
| PR65 | R402H16 | 100KR2F-L1-GP | 64.10035.6DL | R402H16 | 1281.8 | 3127.14 | 0 | NO |
| PR66 | R402H16 | 10KR2F-2-GP | 64.10025.6DL | R402H16 | 1100 | 2895 | 180 | YES |
| PR67 | R402H16 | 4K75R2F-1-GP | 64.47515.6DL | R402H16 | 2453 | 6374 | 0 | NO |
| PR69 | R603H22 | 0R3J-0-U-GP | 63.00000.00L | R603H22 | 250 | 4325 | 180 | NO |
| PR70 | R402H16 | 4K75R2F-1-GP | 64.47515.6DL | R402H16 | 725 | 4225 | 180 | NO |
| PR71 | R402H16 | 0R2J-2-GP | 63.R0034.1DL | R402H16 | 235 | 4240 | 90 | NO |
| PR72 | R603H22 | 0R3J-0-U-GP | 63.00000.00L | R603H22 | 405 | 4140 | 90 | NO |
| PR73 | R402H16 | 10KR2F-2-GP | 64.10025.6DL | R402H16 | 310 | 4290 | 90 | NO |
| PR74 | R603H22 | 0R3J-0-U-GP | 63.00000.00L | R603H22 | 5485.31 | 3655.8 | 0 | NO |
| PR75 | R402H16 | 0R2J-2-GP | 63.R0034.1DL | R402H16 | 5585.31 | 3825.8 | 0 | NO |
| PR77 | R603H22 | 0R3J-0-U-GP | 63.00000.00L | R603H22 | 5665.31 | 3840.8 | 90 | NO |
| PR78 | R402H16 | 10KR2F-2-GP | 64.10025.6DL | R402H16 | 5635.31 | 3750.8 | 0 | NO |
| PR91 | R402H16 | 2K74R2F-GP | 64.27415.6DL | R402H16 | 645 | 4225 | 0 | NO |
| PR150 | R603H22 | 0R3J-0-U-GP | 63.00000.00L | R603H22 | 13663 | 2545 | 270 | YES |
| PR151 | R402H16 | 100KR2F-L1-GP | 64.10035.6DL | R402H16 | 13110 | 2805 | 0 | NO |
| PR152 | R402H16 | 0R2J-2-GP | 63.R0034.1DL | R402H16 | 13070 | 2805 | 180 | NO |
| PR154 | R805H24 | 3D01R5F-GP | 64.3R015.16L | R805H24 | 13150 | 2505 | 90 | YES |
| PR155 | R402H16 | 2K21R2F-GP | 64.22115.6DL | R402H16 | 12935 | 2760 | 180 | YES |
| PR156 | R402H16 | 10D7R2F-GP | 64.10R75.6DL | R402H16 | 13130 | 2915 | 180 | NO |
| PR157 | R402H16 | 51KR2F-L-GP | 64.51025.6DL | R402H16 | 13150 | 2805 | 180 | NO |
| PR158 | R402H16 | 100KR2F-L1-GP | 64.10035.6DL | R402H16 | 13615 | 2685 | 180 | NO |
| PR159 | R603H22 | 0R3J-0-U-GP | 63.00000.00L | R603H22 | 6295.63 | 2381.08 | 270 | YES |
| PR160 | R402H16 | 475KR2F-GP | 64.47535.6DL | R402H16 | 13585 | 2785 | 270 | NO |
| PR161 | R402H16 | 4K42R2F-GP | 64.44215.6DL | R402H16 | 13190 | 2940 | 90 | NO |
| PR162 | R402H16 | 187KR2F-GP | 64.18735.6DL | R402H16 | 13510 | 2815 | 180 | YES |
| PR163 | R402H16 | 100KR2F-L1-GP | 64.10035.6DL | R402H16 | 13590 | 2815 | 180 | YES |
| PR165 | R402H16 | 10KR2F-2-GP | 64.10025.6DL | R402H16 | 13270 | 2905 | 90 | NO |
| PR166 | R805H24 | 3D01R5F-GP | 64.3R015.16L | R805H24 | 6250.63 | 2546.08 | 270 | YES |
| PR167 | R402H16 | 0R2J-2-GP | 63.R0034.1DL | R402H16 | 6313.63 | 2301.08 | 0 | NO |
| PR168 | R402H16 | 4K53R2F-1-GP | 64.45315.6DL | R402H16 | 6213.63 | 2176.08 | 270 | NO |
| PR169 | R402H16 | 187KR2F-GP | 64.18735.6DL | R402H16 | 5923.63 | 2226.08 | 0 | YES |
| PR170 | R402H16 | 475KR2F-GP | 64.47535.6DL | R402H16 | 5830.63 | 2286.08 | 90 | NO |
| PR172 | R402H16 | 10D7R2F-GP | 64.10R75.6DL | R402H16 | 6291.63 | 2176.08 | 90 | NO |
| PR173 | R402H16 | 100KR2F-L1-GP | 64.10035.6DL | R402H16 | 5843.63 | 2226.08 | 0 | YES |
| PR174 | R402H16 | 2K21R2F-GP | 64.22115.6DL | R402H16 | 6419.63 | 2366.08 | 0 | YES |
| PR175 | R402H16 | 100KR2F-L1-GP | 64.10035.6DL | R402H16 | 5741 | 2384 | 270 | NO |
| PR176 | R402H16 | 100KR2F-L1-GP | 64.10035.6DL | R402H16 | 6273.63 | 2301.08 | 180 | NO |
| PR177 | R603H22 | 0R3J-0-U-GP | 63.00000.00L | R603H22 | 5764.34 | 2432.6999999999998 | 90 | YES |
| PR178 | R402H16 | 51KR2F-L-GP | 64.51025.6DL | R402H16 | 6233.63 | 2301.08 | 0 | NO |
| PR179 | R402H16 | 10KR2F-2-GP | 64.10025.6DL | R402H16 | 6138.63 | 2136.08 | 270 | NO |
| PR180 | R402H16 | 80K6R2F-GP | 64.80625.6DL | R402H16 | 6215.63 | 2096.08 | 90 | NO |
| PR182 | R402H16 | 80K6R2F-GP | 64.80625.6DL | R402H16 | 13214 | 2999 | 180 | NO |
| PR628 | R402H16 | 4K7R2F-GP | 64.47015.6DL | R402H16 | 6238.63 | 2381.08 | 90 | NO |
| PR9004 | R402H16 | 0R2J-2-GP | 63.R0034.1DL | R402H16 | 268 | 7294 | 270 | NO |
| PR9006 | R402H16 | 0R2J-2-GP | 63.R0034.1DL | R402H16 | 268 | 7334 | 270 | NO |
| PR9007 | R402H16 | 0R2J-2-GP | 63.R0034.1DL | R402H16 | 253 | 7409 | 0 | NO |
| PR9008 | R402H16 | 0R2J-2-GP | 63.R0034.1DL | R402H16 | 1055 | 2895 | 0 | YES |
| PR9033 | R402H16 | 3K65R2F-1-GP | 64.36515.6DL | R402H16 | 5600.31 | 3349.8 | 270 | NO |
| PR9034 | R402H16 | 2K87R2F-1-GP | 64.28715.6DL | R402H16 | 5600.31 | 3429.8 | 90 | NO |
| PSP2 | CON2C-U | COPPER-CLOSE-GP-U | ZZ.CON2C.XXX | CON2C-U | 13370 | 2815 | 180 | NO |
| PSP3 | CON2C-U | COPPER-CLOSE-GP-U | ZZ.CON2C.XXX | CON2C-U | 6033.63 | 2226.08 | 0 | NO |
| PTC4 | CT7343H83 | SE470UF2VDM-GP | 79.47719.2BL | CT7343H83 | 12345 | 2725 | 180 | NO |
| PTC5 | CT7343H83 | SE470UF2VDM-GP | 79.47719.2BL | CT7343H83 | 12345 | 2145 | 0 | NO |
| PTC6 | CT7343H83 | SE470UF2VDM-GP | 79.47719.2BL | CT7343H83 | 12550 | 2725 | 180 | NO |
| PTC7 | CT7343H83 | SE470UF2VDM-GP | 79.47719.2BL | CT7343H83 | 12550 | 2145 | 0 | NO |
| PTC8 | CT7343H83 | SE470UF2VDM-GP | 79.47719.2BL | CT7343H83 | 6747.63 | 2396.08 | 0 | NO |
| PTC10 | CT7343H83 | SE470UF2VDM-GP | 79.47719.2BL | CT7343H83 | 6748.37 | 2786.92 | 180 | NO |
| PTC38 | CT7343H83 | ST150U6D3VDM-28-GP | 077.51571.0001 | CT7343H83 | 3205 | 1775 | 180 | NO |
| PU1 | QFN22G6050-G6133H60 | TPS53355ADQPR-GP | 074.53355.0073 | QFN22G6050-G6133H60 | 6027.63 | 2408.58 | 270 | NO |
| PU2 | QFN22G6050-G6133H60 | TPS53319DQPR-GP | 74.53319.073 | QFN22G6050-G6133H60 | 2595 | 1520 | 270 | NO |
| PU3 | QFN22G6050-G6133H60 | TPS53355ADQPR-GP | 074.53355.0073 | QFN22G6050-G6133H60 | 13370 | 2632.5 | 90 | NO |
| PU4 | DFN10G3-G315175H40 | TPS74801DRCR-1-GP-U | 074.74801.0033 | DFN10G3-G315175H40 | 2593 | 6359 | 270 | NO |
| PU5 | DFN10G3-G315175H40 | TPS74801DRCR-1-GP-U | 074.74801.0033 | DFN10G3-G315175H40 | 480 | 4260 | 90 | NO |
| PU6 | DFN10G3-G315175H40 | TPS74801DRCR-1-GP-U | 074.74801.0033 | DFN10G3-G315175H40 | 5605.31 | 3580.8 | 0 | NO |
| PU58 | SOT-6H56 | SY8120ABC-GP | 74.08120.04P | SOT-6H56 | 1251 | 2928 | 180 | NO |
| Q4 | TO-92-CBE-4635H591 | PN2907AL-T92-K-GP | 006.02907.001B | TO-92-CBE-4635H591 | 4766.1400000000003 | 1624.93 | 90 | NO |
| Q6 | SOT23DGS2D4H44 | 2N7002K-1-GP | 84.2N702.031 | SOT23DGS2D4H44 | 8207 | 639 | 90 | NO |
| Q9 | SOT23DGS2D4H44 | 2N7002K-1-GP | 84.2N702.031 | SOT23DGS2D4H44 | 7585 | 445 | 90 | NO |
| Q10 | SOT-363H44 | 2N7002DW-7F-GP | 84.27002.C3F | SOT-363H44 | 2535 | 3514 | 270 | NO |
| Q13 | SOT23DGS2D4H44 | 2N7002K-1-GP | 84.2N702.031 | SOT23DGS2D4H44 | 7435 | 445 | 90 | NO |
| Q19 | SOT23DGS2D4H44 | 2N7002K-1-GP | 84.2N702.031 | SOT23DGS2D4H44 | 8770 | 185 | 270 | NO |
| Q20 | SOT23DGS2D4H44 | 2N7002-7F-GP | 84.27002.N31 | SOT23DGS2D4H44 | 797.92 | 3749.37 | 180 | NO |
| Q21 | SOT23DGS2D4H44 | 2N7002K-1-GP | 84.2N702.031 | SOT23DGS2D4H44 | 7371.32 | 0.06 | 270 | NO |
| Q22 | SOT23DGS2D4H44 | 2N7002K-1-GP | 84.2N702.031 | SOT23DGS2D4H44 | 9391 | 674 | 90 | NO |
| Q23 | LFPAK-5PH48-U | PSMN0R9-25YLC-GP | 84.0R925.03N | LFPAK-5PH48-U | 1107 | 7823 | 0 | NO |
| Q24 | SOT23DGS2D4H44 | 2N7002K-1-GP | 84.2N702.031 | SOT23DGS2D4H44 | 4652.7 | 1335.82 | 180 | NO |
| Q25 | SOT23DGS2D4H44 | 2N7002K-1-GP | 84.2N702.031 | SOT23DGS2D4H44 | 4607.8500000000004 | 1495.09 | 180 | NO |
| Q26 | SOT23DGS2D4H44 | 2N7002K-1-GP | 84.2N702.031 | SOT23DGS2D4H44 | 4954.03 | 1553.92 | 180 | NO |
| Q27 | SOT23DGS2D4H44 | 2N7002K-1-GP | 84.2N702.031 | SOT23DGS2D4H44 | 5094.03 | 1553.92 | 180 | NO |
| Q28 | SOT23DGS2D4H44 | 2N7002K-1-GP | 84.2N702.031 | SOT23DGS2D4H44 | 13255.3 | 1445.09 | 180 | NO |
| Q29 | SOT23DGS2D4H44 | 2N7002K-1-GP | 84.2N702.031 | SOT23DGS2D4H44 | 13252.2 | 1256.2 | 180 | NO |
| Q30 | SOT23DGS2D4H44 | 2N7002K-1-GP | 84.2N702.031 | SOT23DGS2D4H44 | 13015.43 | 1560.85 | 180 | NO |
| Q31 | SOT23DGS2D4H44 | 2N7002K-1-GP | 84.2N702.031 | SOT23DGS2D4H44 | 13107.2 | 1353.1 | 270 | NO |
| Q32 | SOT23DGS2D4H44 | 2N7002K-1-GP | 84.2N702.031 | SOT23DGS2D4H44 | 6878.81 | 2011.92 | 180 | NO |
| Q33 | SOT23DGS2D4H44 | 2N7002K-1-GP | 84.2N702.031 | SOT23DGS2D4H44 | 11215 | 2250 | 180 | NO |
| Q34 | SOT23DGS2D4H44 | 2N7002K-1-GP | 84.2N702.031 | SOT23DGS2D4H44 | 6598.81 | 2011.92 | 180 | NO |
| Q35 | SOT23DGS2D4H44 | 2N7002K-1-GP | 84.2N702.031 | SOT23DGS2D4H44 | 6738.81 | 2011.92 | 180 | NO |
| Q36 | SOT23CBE2D4H44 | TMBT3904-GP | 084.03904.0E11 | SOT23CBE2D4H44 | 939.68 | 3749.57 | 0 | NO |
| Q37 | SOT23DGS2D4H44 | 2N7002K-1-GP | 84.2N702.031 | SOT23DGS2D4H44 | 13682.18 | 1776.02 | 0 | NO |
| Q38 | SOT23DGS2D4H44 | 2N7002K-1-GP | 84.2N702.031 | SOT23DGS2D4H44 | 11360 | 2250 | 180 | NO |
| Q39 | SOT23DGS2D4H44 | 2N7002K-1-GP | 84.2N702.031 | SOT23DGS2D4H44 | 11505 | 2250 | 180 | NO |
| Q40 | SOT23DGS2D4H44 | 2N7002K-1-GP | 84.2N702.031 | SOT23DGS2D4H44 | 10300 | 539 | 180 | YES |
| Q41 | SOT23CBE2D4H44 | TMBT3904-GP | 084.03904.0E11 | SOT23CBE2D4H44 | 1082.47 | 3749.06 | 180 | NO |
| Q42 | SOT23DGS2D4H44 | 2N7002K-1-GP | 84.2N702.031 | SOT23DGS2D4H44 | 2098.5700000000002 | 1343 | 90 | NO |
| Q43 | SOT23CBE2D4H44 | DSS4240T-7-GP | 084.04240.0011 | SOT23CBE2D4H44 | 2228.54 | 1487.61 | 0 | NO |
| Q45 | SOT23DGS2D4H44 | 2N7002K-1-GP | 84.2N702.031 | SOT23DGS2D4H44 | 1561.85 | 3318.11 | 90 | NO |
| Q46 | SOT23CBE2D4H44 | DSS4240T-7-GP | 084.04240.0011 | SOT23CBE2D4H44 | 1409.17 | 3332.65 | 90 | NO |
| Q93 | SOT23DGS2D4H44 | 2N7002K-1-GP | 84.2N702.031 | SOT23DGS2D4H44 | 859.5 | 6916.5 | 0 | NO |
| Q94 | SOT23DGS2D4H44 | 2N7002K-1-GP | 84.2N702.031 | SOT23DGS2D4H44 | 999.5 | 6916.5 | 0 | NO |
| Q95 | SOT23DGS2D4H44 | 2N7002K-1-GP | 84.2N702.031 | SOT23DGS2D4H44 | 278 | 6914 | 90 | NO |
| Q96 | SOT23DGS2D4H44 | 2N7002K-1-GP | 84.2N702.031 | SOT23DGS2D4H44 | 477 | 6903 | 90 | NO |
| Q3202 | SOT23DGS2D4H44 | 2N7002K-1-GP | 84.2N702.031 | SOT23DGS2D4H44 | 8604 | 162 | 90 | YES |
| Q3203 | SOIC8H79 | P2003EVG-GP | 84.02003.A37 | SOIC8H79 | 10113 | 629 | 90 | NO |
| R1 | R402H16 | 0R2J-2-GP | 63.R0034.1DL | R402H16 | 9947 | 1028 | 0 | YES |
| R2 | R402H16 | 20KR2F-L-GP | 64.20025.6DL | R402H16 | 12910 | 2950 | 90 | NO |
| R3 | R402H16 | 0R2J-2-GP | 63.R0034.1DL | R402H16 | 7993.1 | 263.43 | 90 | NO |
| R4 | R402H16 | 0R2J-2-GP | 63.R0034.1DL | R402H16 | 10106.76 | 432.62 | 0 | NO |
| R5 | R0201H12 | 33R1J-GP | 63.3303C.1IL | R0201H12 | 9434 | 1458 | 180 | YES |
| R6 | R0201H12 | 33R1J-GP | 63.3303C.1IL | R0201H12 | 9512 | 1459 | 180 | YES |
| R7 | R0201H12 | 33R1J-GP | 63.3303C.1IL | R0201H12 | 9315 | 1457 | 180 | YES |
| R8 | R0201H12 | 33R1J-GP | 63.3303C.1IL | R0201H12 | 9394 | 1456 | 180 | YES |
| R9 | R0201H12 | 33R1J-GP | 63.3303C.1IL | R0201H12 | 9276 | 1438 | 180 | YES |
| R12 | R402H16 | 0R2J-2-GP | 63.R0034.1DL | R402H16 | 10006.83 | 474.5 | 0 | NO |
| R13 | R402H16 | 0R2J-2-GP | 63.R0034.1DL | R402H16 | 5914.63 | 2113.08 | 90 | NO |
| R14 | R402H16 | 0R2J-2-GP | 63.R0034.1DL | R402H16 | 12910 | 3000 | 270 | NO |
| R15 | R402H16 | 0R2J-2-GP | 63.R0034.1DL | R402H16 | 320 | 4750 | 0 | NO |
| R16 | R402H16 | 0R2J-2-GP | 63.R0034.1DL | R402H16 | 490 | 4750 | 0 | NO |
| R17 | R402H16 | 0R2J-2-GP | 63.R0034.1DL | R402H16 | 640 | 4925 | 180 | NO |
| R18 | R402H16 | 0R2J-2-GP | 63.R0034.1DL | R402H16 | 469 | 4922 | 180 | NO |
| R19 | R402H16 | 0R2J-2-GP | 63.R0034.1DL | R402H16 | 2351 | 4645 | 180 | YES |
| R20 | R402H14 | 100R2F-L1-GP-U | 64.10005.6DL | R402H14 | 1330 | 4595 | 0 | NO |
| R21 | R402H16 | 0R2J-2-GP | 63.R0034.1DL | R402H16 | 2518 | 4647 | 180 | YES |
| R22 | R402H16 | 0R2J-2-GP | 63.R0034.1DL | R402H16 | 2781 | 4763 | 180 | NO |
| R23 | R402H16 | 10KR2F-2-GP | 64.10025.6DL | R402H16 | 1370 | 4595 | 0 | NO |
| R25 | R402H16 | 4K7R2F-GP | 64.47015.6DL | R402H16 | 7918 | 276 | 180 | NO |
| R26 | R402H16 | 0R2J-2-GP | 63.R0034.1DL | R402H16 | 2606 | 4748 | 180 | NO |
| R27 | R402H16 | 0R2J-2-GP | 63.R0034.1DL | R402H16 | 9039 | 1125 | 90 | YES |
| R28 | R402H16 | 0R2J-2-GP | 63.R0034.1DL | R402H16 | 9545 | 720 | 270 | YES |
| R29 | R402H16 | 100KR2F-L1-GP | 64.10035.6DL | R402H16 | 8481 | 859 | 180 | YES |
| R30 | R402H16 | 4K7R2F-GP | 64.47015.6DL | R402H16 | 10134.780000000001 | 491.09 | 90 | NO |
| R31 | R402H16 | 4K7R2F-GP | 64.47015.6DL | R402H16 | 10051.76 | 432.62 | 0 | NO |
| R32 | R402H16 | 0R2J-2-GP | 63.R0034.1DL | R402H16 | 2549 | 4386 | 270 | NO |
| R33 | R603H22 | 0R3J-0-U-GP | 63.00000.00L | R603H22 | 1425.01 | 4111.3100000000004 | 90 | NO |
| R39 | R402H16 | 0R2J-2-GP | 63.R0034.1DL | R402H16 | 2576 | 4225 | 270 | NO |
| R40 | R402H16 | 0R2J-2-GP | 63.R0034.1DL | R402H16 | 2126.38 | 4418.45 | 90 | YES |
| R41 | R603H22 | 1KR3F-GP | 64.10015.55L | R603H22 | 9494 | 441 | 270 | YES |
| R42 | R402H16 | 0R2J-2-GP | 63.R0034.1DL | R402H16 | 9870.39 | 1555.15 | 180 | YES |
| R43 | R603H22 | 1KR3F-GP | 64.10015.55L | R603H22 | 7190.87 | 2019.42 | 90 | YES |
| R44 | R402H16 | 10KR2F-2-GP | 64.10025.6DL | R402H16 | 6320 | 3226 | 180 | NO |
| R45 | R402H16 | 10KR2F-2-GP | 64.10025.6DL | R402H16 | 6615 | 3401 | 90 | NO |
| R46 | R402H16 | 100KR2F-L1-GP | 64.10035.6DL | R402H16 | 1629 | 2392.9 | 180 | NO |
| R47 | R402H16 | 0R2J-2-GP | 63.R0034.1DL | R402H16 | 1247 | 3923 | 90 | NO |
| R48 | R402H16 | 0R2J-2-GP | 63.R0034.1DL | R402H16 | 1345.14 | 3739.85 | 270 | NO |
| R49 | R402H16 | 0R2J-2-GP | 63.R0034.1DL | R402H16 | 1460 | 3690 | 180 | NO |
| R50 | R402H16 | 0R2J-2-GP | 63.R0034.1DL | R402H16 | 1591 | 3792 | 270 | NO |
| R52 | R402H16 | 0R2J-2-GP | 63.R0034.1DL | R402H16 | 2095.38 | 4254.45 | 90 | YES |
| R53 | R402H16 | 0R2J-2-GP | 63.R0034.1DL | R402H16 | 1345.71 | 4080.96 | 180 | NO |
| R55 | R402H16 | 10KR2F-2-GP | 64.10025.6DL | R402H16 | 6540 | 3401 | 90 | NO |
| R56 | R402H16 | 0R2J-2-GP | 63.R0034.1DL | R402H16 | 4558 | 972 | 180 | NO |
| R58 | R402H16 | 4K7R2F-GP | 64.47015.6DL | R402H16 | 8155 | 188 | 180 | NO |
| R59 | R402H16 | 10KR2F-2-GP | 64.10025.6DL | R402H16 | 6615 | 3766 | 90 | NO |
| R60 | R402H16 | 10KR2F-2-GP | 64.10025.6DL | R402H16 | 6275 | 3856 | 180 | NO |
| R61 | R402H16 | 10KR2F-2-GP | 64.10025.6DL | R402H16 | 6275 | 3776 | 180 | NO |
| R62 | R402H16 | 10KR2F-2-GP | 64.10025.6DL | R402H16 | 6540 | 3766 | 90 | NO |
| R63 | R402H16 | 10KR2F-2-GP | 64.10025.6DL | R402H16 | 8524 | 858 | 180 | YES |
| R64 | R402H16 | 0R2J-2-GP | 63.R0034.1DL | R402H16 | 2115.38 | 4419.45 | 270 | NO |
| R65 | R402H16 | 0R2J-2-GP | 63.R0034.1DL | R402H16 | 2117.38 | 4256.45 | 270 | NO |
| R66 | R402H16 | 0R2J-2-GP | 63.R0034.1DL | R402H16 | 1912 | 4033 | 270 | YES |
| R67 | R402H16 | 0R2J-2-GP | 63.R0034.1DL | R402H16 | 1914 | 4198 | 270 | YES |
| R68 | R402H16 | 20KR2F-L-GP | 64.20025.6DL | R402H16 | 5914.63 | 2153.08 | 270 | NO |
| R69 | R402H16 | 0R2J-2-GP | 63.R0034.1DL | R402H16 | 8085 | 865 | 270 | NO |
| R73 | R0201H12 | 33R1J-GP | 63.3303C.1IL | R0201H12 | 968.6 | 4952.07 | 0 | NO |
| R74 | R402H16 | 0R2J-2-GP | 63.R0034.1DL | R402H16 | 6240 | 3356 | 180 | NO |
| R75 | R402H16 | 0R2J-2-GP | 63.R0034.1DL | R402H16 | 6280 | 3356 | 180 | NO |
| R76 | R402H16 | 0R2J-2-GP | 63.R0034.1DL | R402H16 | 6291.63 | 2094.08 | 90 | NO |
| R77 | R402H16 | 0R2J-2-GP | 63.R0034.1DL | R402H16 | 6320 | 3356 | 0 | NO |
| R78 | R402H16 | 0R2J-2-GP | 63.R0034.1DL | R402H16 | 6135 | 3553.83 | 180 | NO |
| R79 | R402H16 | 0R2J-2-GP | 63.R0034.1DL | R402H16 | 6291.63 | 2135.08 | 90 | NO |
| R80 | R402H16 | 0R2J-2-GP | 63.R0034.1DL | R402H16 | 13173 | 2999 | 180 | NO |
| R85 | R402H16 | 150R2F-1-GP | 64.15005.6DL | R402H16 | 8965 | 150 | 180 | NO |
| R87 | R402H16 | 0R2J-2-GP | 63.R0034.1DL | R402H16 | 6540 | 3446 | 90 | NO |
| R88 | R402H16 | 0R2J-2-GP | 63.R0034.1DL | R402H16 | 6540 | 3721 | 90 | NO |
| R89 | R402H16 | 0R2J-2-GP | 63.R0034.1DL | R402H16 | 6320 | 3776 | 180 | NO |
| R90 | R402H16 | 0R2J-2-GP | 63.R0034.1DL | R402H16 | 7575 | 1188 | 270 | NO |
| R92 | R603H22 | 1R3F-GP | 64.1R005.55L | R603H22 | 6555 | 3576 | 90 | NO |
| R96 | R402H16 | 10KR2F-2-GP | 64.10025.6DL | R402H16 | 6170 | 3886 | 180 | NO |
| R97 | R402H16 | 10KR2F-2-GP | 64.10025.6DL | R402H16 | 6170 | 3776 | 0 | NO |
| R98 | R402H16 | 10KR2F-2-GP | 64.10025.6DL | R402H16 | 6080.9 | 3323.6 | 0 | NO |
| R99 | R402H16 | 10KR2F-2-GP | 64.10025.6DL | R402H16 | 6067 | 3442 | 270 | NO |
| R100 | R402H16 | 10KR2F-2-GP | 64.10025.6DL | R402H16 | 6230 | 3776 | 0 | NO |
| R101 | R402H16 | 10KR2F-2-GP | 64.10025.6DL | R402H16 | 6230 | 3886 | 180 | NO |
| R140 | R402H16 | 4K7R2F-GP | 64.47015.6DL | R402H16 | 5140 | 7975 | 0 | YES |
| R141 | R402H16 | 4K7R2F-GP | 64.47015.6DL | R402H16 | 13020 | 7050 | 0 | YES |
| R142 | R402H16 | 4K7R2F-GP | 64.47015.6DL | R402H16 | 5300 | 7975 | 0 | YES |
| R143 | R402H16 | 4K7R2F-GP | 64.47015.6DL | R402H16 | 2850 | 7505 | 0 | YES |
| R144 | R402H16 | 4K7R2F-GP | 64.47015.6DL | R402H16 | 4980 | 8025 | 0 | YES |
| R145 | R402H16 | 4K7R2F-GP | 64.47015.6DL | R402H16 | 8575 | 7800 | 0 | YES |
| R146 | R402H16 | 4K7R2F-GP | 64.47015.6DL | R402H16 | 3010 | 7460 | 0 | YES |
| R147 | R402H16 | 4K7R2F-GP | 64.47015.6DL | R402H16 | 4808 | 8025 | 0 | YES |
| R148 | R402H16 | 4K7R2F-GP | 64.47015.6DL | R402H16 | 2115 | 5425 | 90 | YES |
| R149 | R402H16 | 4K7R2F-GP | 64.47015.6DL | R402H16 | 2115 | 5465 | 90 | YES |
| R150 | R402H16 | 4K7R2F-GP | 64.47015.6DL | R402H16 | 2115 | 5505 | 90 | NO |
| R151 | R402H16 | 4K7R2F-GP | 64.47015.6DL | R402H16 | 2115 | 5345 | 90 | NO |
| R152 | R402H16 | 4K7R2F-GP | 64.47015.6DL | R402H16 | 2115 | 5385 | 90 | YES |
| R153 | R402H16 | 4K7R2F-GP | 64.47015.6DL | R402H16 | 2115 | 5425 | 90 | NO |
| R154 | R402H16 | 4K7R2F-GP | 64.47015.6DL | R402H16 | 2115 | 5385 | 90 | NO |
| R155 | R402H16 | 4K7R2F-GP | 64.47015.6DL | R402H16 | 1915 | 5830 | 180 | YES |
| R156 | R402H16 | 4K7R2F-GP | 64.47015.6DL | R402H16 | 1643.27 | 4477.21 | 90 | NO |
| R157 | R402H16 | 4K7R2F-GP | 64.47015.6DL | R402H16 | 8704 | 7874 | 0 | YES |
| R158 | R402H16 | 4K7R2F-GP | 64.47015.6DL | R402H16 | 3170 | 7465 | 0 | YES |
| R159 | R402H16 | 0R2J-2-GP | 63.R0034.1DL | R402H16 | 2320 | 5860 | 270 | NO |
| R160 | R402H16 | 4K7R2F-GP | 64.47015.6DL | R402H16 | 1955 | 6000 | 180 | NO |
| R161 | R402H16 | 4K7R2F-GP | 64.47015.6DL | R402H16 | 1915 | 5925 | 180 | NO |
| R162 | R402H16 | 0R2J-2-GP | 63.R0034.1DL | R402H16 | 2320 | 5900 | 270 | NO |
| R163 | R402H16 | 4K7R2F-GP | 64.47015.6DL | R402H16 | 552.61 | 5091.41 | 0 | NO |
| R164 | R402H16 | 4K7R2F-GP | 64.47015.6DL | R402H16 | 1915 | 6000 | 0 | NO |
| R165 | R402H16 | 4K7R2F-GP | 64.47015.6DL | R402H16 | 1955 | 5925 | 0 | NO |
| R166 | R402H16 | 4K7R2F-GP | 64.47015.6DL | R402H16 | 761.7 | 2609.1999999999998 | 180 | NO |
| R173 | R402H16 | 4K7R2F-GP | 64.47015.6DL | R402H16 | 9380 | 250 | 0 | NO |
| R174 | R402H16 | 4K7R2F-GP | 64.47015.6DL | R402H16 | 9289.7000000000007 | 235.4 | 90 | NO |
| R175 | R402H16 | 4K7R2F-GP | 64.47015.6DL | R402H16 | 8865.2000000000007 | 150.02000000000001 | 180 | NO |
| R176 | R402H16 | 4K7R2F-GP | 64.47015.6DL | R402H16 | 8913.01 | 148.77000000000001 | 0 | NO |
| R177 | R402H16 | 4K7R2F-GP | 64.47015.6DL | R402H16 | 9020 | 3540 | 90 | NO |
| R178 | R402H16 | 4K7R2F-GP | 64.47015.6DL | R402H16 | 9020 | 3456 | 270 | NO |
| R188 | R402H16 | 4K7R2F-GP | 64.47015.6DL | R402H16 | 10491.61 | 101.07 | 180 | YES |
| R189 | R402H16 | 4K7R2F-GP | 64.47015.6DL | R402H16 | 10441.61 | 195.68 | 0 | YES |
| R190 | R402H16 | 0R2J-2-GP | 63.R0034.1DL | R402H16 | 10059.280000000001 | 276.05 | 90 | YES |
| R191 | R402H16 | 0R2J-2-GP | 63.R0034.1DL | R402H16 | 10059.280000000001 | 236.05 | 90 | YES |
| R192 | R402H16 | 8K2R2J-3-GP | 63.82234.1DL | R402H16 | 2960 | 5785 | 270 | YES |
| R193 | R402H16 | 8K2R2J-3-GP | 63.82234.1DL | R402H16 | 2960 | 5830 | 270 | YES |
| R194 | R402H16 | 8K2R2J-3-GP | 63.82234.1DL | R402H16 | 2960 | 5885 | 270 | YES |
| R195 | R402H16 | 4K7R2F-GP | 64.47015.6DL | R402H16 | 10441.469999999999 | 120.9 | 180 | YES |
| R196 | R402H16 | 4K7R2F-GP | 64.47015.6DL | R402H16 | 10504.12 | 183.57 | 90 | YES |
| R197 | R402H16 | 8K2R2J-3-GP | 63.82234.1DL | R402H16 | 2959.88 | 5781.65 | 90 | NO |
| R198 | R402H16 | 8K2R2J-3-GP | 63.82234.1DL | R402H16 | 2959.88 | 5831.65 | 90 | NO |
| R199 | R402H16 | 8K2R2J-3-GP | 63.82234.1DL | R402H16 | 2959.88 | 5886.65 | 90 | NO |
| R200 | R402H16 | 8K2R2J-3-GP | 63.82234.1DL | R402H16 | 2540.1999999999998 | 5813.81 | 270 | NO |
| R201 | R402H16 | 49D9R2D-GP | 64.49R96.6DL | R402H16 | 10358.299999999999 | 92.19 | 180 | YES |
| R202 | R402H16 | 49D9R2D-GP | 64.49R96.6DL | R402H16 | 10401.4 | 92.63 | 180 | YES |
| R203 | R402H16 | 0R2J-2-GP | 63.R0034.1DL | R402H16 | 10359.81 | 28.42 | 90 | YES |
| R204 | R402H16 | 0R2J-2-GP | 63.R0034.1DL | R402H16 | 10435.629999999999 | 29.48 | 90 | YES |
| R205 | R402H16 | 4K7R2F-GP | 64.47015.6DL | R402H16 | 7170.5 | 179.2 | 90 | YES |
| R206 | R402H16 | 4K7R2F-GP | 64.47015.6DL | R402H16 | 5525 | 1375.97 | 270 | NO |
| R207 | R402H16 | 4K7R2F-GP | 64.47015.6DL | R402H16 | 7138.63 | 372.36 | 270 | YES |
| R208 | R402H16 | 0R2J-2-GP | 63.R0034.1DL | R402H16 | 2620 | 5885 | 270 | YES |
| R209 | R402H16 | 4K7R2F-GP | 64.47015.6DL | R402H16 | 13195 | 7075 | 0 | YES |
| R210 | R402H16 | 4K7R2F-GP | 64.47015.6DL | R402H16 | 2675 | 7505 | 0 | YES |
| R211 | R402H16 | 4K7R2F-GP | 64.47015.6DL | R402H16 | 7208.4 | 581.4 | 0 | NO |
| R212 | R402H16 | 0R2J-2-GP | 63.R0034.1DL | R402H16 | 2620 | 5930 | 270 | YES |
| R213 | R402H16 | 4K7R2F-GP | 64.47015.6DL | R402H16 | 7115.1 | 121.8 | 180 | YES |
| R214 | R402H16 | 4K7R2F-GP | 64.47015.6DL | R402H16 | 5599.7 | 1369.09 | 270 | NO |
| R215 | R402H16 | 4K7R2F-GP | 64.47015.6DL | R402H16 | 10707.33 | 429.23 | 180 | NO |
| R216 | R402H16 | 4K7R2F-GP | 64.47015.6DL | R402H16 | 10688.09 | 150.41999999999999 | 0 | NO |
| R217 | R402H16 | 4K7R2F-GP | 64.47015.6DL | R402H16 | 10768.39 | 140.69999999999999 | 270 | NO |
| R218 | R402H16 | 4K7R2F-GP | 64.47015.6DL | R402H16 | 12479.68 | 1411.79 | 90 | NO |
| R219 | R402H16 | 4K7R2F-GP | 64.47015.6DL | R402H16 | 10641.83 | 488.32 | 90 | NO |
| R220 | R402H16 | 4K7R2F-GP | 64.47015.6DL | R402H16 | 2245 | 5545 | 270 | YES |
| R221 | R402H16 | 4K7R2F-GP | 64.47015.6DL | R402H16 | 950 | 4804 | 270 | YES |
| R222 | R402H16 | 4K7R2F-GP | 64.47015.6DL | R402H16 | 10774.76 | 182.66 | 90 | NO |
| R223 | R402H16 | 4K7R2F-GP | 64.47015.6DL | R402H16 | 1855 | 4595 | 0 | YES |
| R224 | R402H16 | 4K7R2F-GP | 64.47015.6DL | R402H16 | 1881.5 | 4602.05 | 0 | NO |
| R225 | R402H16 | 4K7R2F-GP | 64.47015.6DL | R402H16 | 792 | 4786 | 270 | YES |
| R228 | R402H16 | 4K7R2F-GP | 64.47015.6DL | R402H16 | 1855 | 5725 | 180 | NO |
| R229 | R402H16 | 4K7R2F-GP | 64.47015.6DL | R402H16 | 1895 | 5725 | 180 | NO |
| R230 | R402H16 | 4K7R2F-GP | 64.47015.6DL | R402H16 | 725 | 5065 | 270 | NO |
| R231 | R402H16 | 1KR2F-3-GP | 64.10015.6DL | R402H16 | 1355.51 | 6484.36 | 90 | NO |
| R232 | R402H16 | 1KR2F-3-GP | 64.10015.6DL | R402H16 | 1450.69 | 6366.2 | 90 | NO |
| R233 | R402H16 | 100KR2F-L1-GP | 64.10035.6DL | R402H16 | 1075 | 4595 | 0 | NO |
| R234 | R402H16 | 100KR2F-L1-GP | 64.10035.6DL | R402H16 | 925 | 4715 | 0 | NO |
| R235 | R402H16 | 100KR2F-L1-GP | 64.10035.6DL | R402H16 | 1035 | 4595 | 180 | NO |
| R236 | R402H16 | 100KR2F-L1-GP | 64.10035.6DL | R402H16 | 725 | 4985 | 270 | YES |
| R237 | R402H16 | 100KR2F-L1-GP | 64.10035.6DL | R402H16 | 1155 | 4595 | 180 | NO |
| R238 | R402H16 | 0R2J-2-GP | 63.R0034.1DL | R402H16 | 591 | 4742 | 90 | NO |
| R239 | R402H16 | 0R2J-2-GP | 63.R0034.1DL | R402H16 | 591 | 4701 | 90 | NO |
| R240 | R402H16 | 0R2J-2-GP | 63.R0034.1DL | R402H16 | 803.17 | 4900.8599999999997 | 90 | YES |
| R241 | R402H16 | 0R2J-2-GP | 63.R0034.1DL | R402H16 | 803.17 | 4940.8599999999997 | 90 | YES |
| R242 | R402H16 | 0R2J-2-GP | 63.R0034.1DL | R402H16 | 2245.38 | 4623 | 270 | YES |
| R243 | R402H16 | 0R2J-2-GP | 63.R0034.1DL | R402H16 | 2245.38 | 4663 | 270 | YES |
| R244 | R402H16 | 0R2J-2-GP | 63.R0034.1DL | R402H16 | 2525 | 4775 | 90 | YES |
| R245 | R402H16 | 0R2J-2-GP | 63.R0034.1DL | R402H16 | 2525 | 4815 | 90 | YES |
| R246 | R402H16 | 0R2J-2-GP | 63.R0034.1DL | R402H16 | 2125.02 | 4796.1899999999996 | 270 | YES |
| R247 | R402H16 | 0R2J-2-GP | 63.R0034.1DL | R402H16 | 2125.02 | 4756.1899999999996 | 270 | YES |
| R248 | R402H16 | 240R2F-1-GP | 64.24005.6DL | R402H16 | 1387.69 | 5767.2 | 180 | NO |
| R249 | R402H16 | 0R2J-2-GP | 63.R0034.1DL | R402H16 | 2515 | 4860 | 90 | YES |
| R250 | R402H16 | 4K7R2F-GP | 64.47015.6DL | R402H16 | 7201 | 398 | 0 | YES |
| R251 | R402H16 | 0R2J-2-GP | 63.R0034.1DL | R402H16 | 2515 | 4900 | 90 | YES |
| R252 | R402H16 | 4K7R2F-GP | 64.47015.6DL | R402H16 | 7248.9 | 581.29999999999995 | 180 | NO |
| R253 | R402H16 | 4K7R2F-GP | 64.47015.6DL | R402H16 | 10686.73 | 226.45 | 180 | NO |
| R254 | R402H16 | 4K7R2F-GP | 64.47015.6DL | R402H16 | 12464.84 | 1452.17 | 90 | NO |
| R255 | R402H16 | 4K7R2F-GP | 64.47015.6DL | R402H16 | 686 | 5269 | 90 | YES |
| R257 | R402H16 | 4K7R2F-GP | 64.47015.6DL | R402H16 | 2115 | 5705 | 90 | NO |
| R258 | R402H16 | 100KR2F-L1-GP | 64.10035.6DL | R402H16 | 1115 | 4595 | 0 | NO |
| R259 | R402H16 | 100KR2F-L1-GP | 64.10035.6DL | R402H16 | 1035 | 4595 | 0 | YES |
| R261 | R402H16 | 0R2J-2-GP | 63.R0034.1DL | R402H16 | 2635.38 | 4776 | 270 | YES |
| R262 | R402H16 | 0R2J-2-GP | 63.R0034.1DL | R402H16 | 2635.38 | 4816 | 270 | YES |
| R264 | R402H16 | 2K2R2J-2-GP | 63.22234.1DL | R402H16 | 725 | 5225 | 90 | YES |
| R265 | R402H16 | 0R2J-2-GP | 63.R0034.1DL | R402H16 | 2404 | 2321 | 180 | NO |
| R266 | R402H16 | 2K2R2J-2-GP | 63.22234.1DL | R402H16 | 2729 | 2950 | 0 | NO |
| R267 | R402H16 | 2K2R2J-2-GP | 63.22234.1DL | R402H16 | 2363.31 | 2320.8000000000002 | 0 | NO |
| R268 | R402H16 | 0R2J-2-GP | 63.R0034.1DL | R402H16 | 7153.9 | 313.8 | 0 | YES |
| R269 | R402H16 | 0R2J-2-GP | 63.R0034.1DL | R402H16 | 9908.69 | 231.21 | 270 | NO |
| R270 | R402H16 | 0R2J-2-GP | 63.R0034.1DL | R402H16 | 9908.69 | 272.48 | 270 | NO |
| R271 | R402H16 | 4K7R2F-GP | 64.47015.6DL | R402H16 | 8410 | 7765 | 0 | YES |
| R272 | R402H16 | 4K7R2F-GP | 64.47015.6DL | R402H16 | 8875 | 7830 | 0 | YES |
| R273 | R402H16 | 0R2J-2-GP | 63.R0034.1DL | R402H16 | 7151.3 | 549 | 0 | YES |
| R274 | R402H16 | 0R2J-2-GP | 63.R0034.1DL | R402H16 | 5524.8 | 1335.5 | 90 | NO |
| R275 | R402H16 | 0R2J-2-GP | 63.R0034.1DL | R402H16 | 8675 | 145 | 180 | NO |
| R276 | R402H16 | 4K7R2F-GP | 64.47015.6DL | R402H16 | 13360 | 7035 | 0 | YES |
| R277 | R402H16 | 0R2J-2-GP | 63.R0034.1DL | R402H16 | 10732.5 | 307.5 | 180 | YES |
| R278 | R402H16 | 0R2J-2-GP | 63.R0034.1DL | R402H16 | 10882.25 | 141.77000000000001 | 90 | NO |
| R279 | R402H16 | 0R2J-2-GP | 63.R0034.1DL | R402H16 | 2200 | 4866 | 90 | NO |
| R280 | R402H16 | 0R2J-2-GP | 63.R0034.1DL | R402H16 | 2515 | 4941 | 270 | YES |
| R281 | R402H16 | 0R2J-2-GP | 63.R0034.1DL | R402H16 | 1462 | 4595 | 180 | NO |
| R283 | R402H16 | 22R2J-2-GP | 63.22034.1DL | R402H16 | 1450 | 4600 | 180 | YES |
| R285 | R402H16 | 22R2J-2-GP | 63.22034.1DL | R402H16 | 1410 | 4600 | 180 | YES |
| R286 | R402H16 | 0R2J-2-GP | 63.R0034.1DL | R402H16 | 1506.32 | 4518.55 | 180 | NO |
| R288 | R402H16 | 47KR2F-GP | 64.47025.6DL | R402H16 | 1334.09 | 4263.37 | 90 | YES |
| R289 | R402H16 | 0R2J-2-GP | 63.R0034.1DL | R402H16 | 825 | 5343 | 90 | NO |
| R290 | R402H16 | 0R2J-2-GP | 63.R0034.1DL | R402H16 | 825 | 5383 | 90 | NO |
| R291 | R402H16 | 0R2J-2-GP | 63.R0034.1DL | R402H16 | 1334.08 | 4303.6499999999996 | 90 | YES |
| R292 | R402H16 | 0R2J-2-GP | 63.R0034.1DL | R402H16 | 7151.1 | 517.96 | 270 | NO |
| R293 | R402H16 | 4K7R2F-GP | 64.47015.6DL | R402H16 | 390 | 4845 | 90 | NO |
| R294 | R402H16 | 4K7R2F-GP | 64.47015.6DL | R402H16 | 385 | 4660 | 90 | NO |
| R295 | R402H16 | 4K7R2F-GP | 64.47015.6DL | R402H16 | 575 | 4830 | 270 | NO |
| R296 | R402H16 | 4K7R2F-GP | 64.47015.6DL | R402H16 | 575 | 5020 | 270 | NO |
| R297 | R402H16 | 4K7R2F-GP | 64.47015.6DL | R402H16 | 1000 | 5925 | 270 | NO |
| R298 | R402H14 | 10R2F-L-GP | 64.10R05.6DL | R402H14 | 1000 | 5695 | 270 | NO |
| R299 | R402H16 | 0R2J-2-GP | 63.R0034.1DL | R402H16 | 825 | 5545 | 90 | YES |
| R300 | R402H16 | 4K7R2F-GP | 64.47015.6DL | R402H16 | 2419 | 4556 | 90 | YES |
| R301 | R402H16 | 10KR2F-2-GP | 64.10025.6DL | R402H16 | 1615 | 5000 | 180 | YES |
| R302 | R402H16 | 0R2J-2-GP | 63.R0034.1DL | R402H16 | 5582.63 | 1352.2 | 0 | NO |
| R303 | R402H16 | 0R2J-2-GP | 63.R0034.1DL | R402H16 | 7151.3 | 474 | 180 | YES |
| R304 | R402H16 | 0R2J-2-GP | 63.R0034.1DL | R402H16 | 7151.1 | 558.6 | 270 | NO |
| R305 | R402H16 | 0R2J-2-GP | 63.R0034.1DL | R402H16 | 7581 | 262 | 90 | NO |
| R306 | R402H16 | 4K7R2F-GP | 64.47015.6DL | R402H16 | 2419 | 4736 | 90 | YES |
| R307 | R402H16 | 4K7R2F-GP | 64.47015.6DL | R402H16 | 2711 | 4673 | 270 | NO |
| R308 | R402H16 | 0R2J-2-GP | 63.R0034.1DL | R402H16 | 1845 | 5470 | 0 | YES |
| R309 | R402H16 | 4K7R2F-GP | 64.47015.6DL | R402H16 | 2711 | 4858 | 270 | NO |
| R310 | R402H16 | 0R2J-2-GP | 63.R0034.1DL | R402H16 | 2245 | 5505 | 270 | YES |
| R311 | R402H16 | 0R2J-2-GP | 63.R0034.1DL | R402H16 | 2055 | 5725 | 180 | NO |
| R312 | R402H16 | 4K7R2F-GP | 64.47015.6DL | R402H16 | 2629 | 4321 | 0 | NO |
| R313 | R402H16 | 4K7R2F-GP | 64.47015.6DL | R402H16 | 2449 | 4326 | 0 | NO |
| R314 | R402H16 | 4K7R2F-GP | 64.47015.6DL | R402H16 | 2018 | 4455 | 0 | YES |
| R315 | R402H16 | 0R2J-2-GP | 63.R0034.1DL | R402H16 | 2425 | 5195 | 180 | NO |
| R316 | R402H16 | 0R2J-2-GP | 63.R0034.1DL | R402H16 | 2115 | 5255 | 270 | YES |
| R317 | R402H16 | 8K2R2J-3-GP | 63.82234.1DL | R402H16 | 923.6 | 5650.1 | 180 | YES |
| R318 | R402H16 | 0R2J-2-GP | 63.R0034.1DL | R402H16 | 2115 | 5215 | 270 | YES |
| R319 | R402H16 | 0R2J-2-GP | 63.R0034.1DL | R402H16 | 2115 | 5255 | 270 | NO |
| R320 | R402H16 | 0R2J-2-GP | 63.R0034.1DL | R402H16 | 2115 | 5215 | 270 | NO |
| R321 | R402H16 | 0R2J-2-GP | 63.R0034.1DL | R402H16 | 2425 | 5275 | 0 | NO |
| R322 | R402H16 | 0R2J-2-GP | 63.R0034.1DL | R402H16 | 2115 | 5345 | 270 | YES |
| R323 | R402H16 | 4K7R2F-GP | 64.47015.6DL | R402H16 | 2331.4299999999998 | 4859.29 | 90 | YES |
| R324 | R402H16 | 10KR2F-2-GP | 64.10025.6DL | R402H16 | 825 | 5585 | 270 | NO |
| R325 | R402H16 | 4K7R2F-GP | 64.47015.6DL | R402H16 | 2026.38 | 4358.45 | 0 | YES |
| R326 | R402H16 | 0R2J-2-GP | 63.R0034.1DL | R402H16 | 6655 | 2120 | 270 | NO |
| R327 | R402H16 | 4K7R2F-GP | 64.47015.6DL | R402H16 | 2208.38 | 4336.45 | 0 | YES |
| R328 | R402H16 | 4K7R2F-GP | 64.47015.6DL | R402H16 | 2209.69 | 4366.72 | 0 | NO |
| R329 | R402H16 | 0R2J-2-GP | 63.R0034.1DL | R402H16 | 7153.8 | 237.8 | 180 | YES |
| R330 | R402H16 | 4K7R2F-GP | 64.47015.6DL | R402H16 | 1978.41 | 4321.42 | 0 | NO |
| R331 | R402H16 | 4K7R2F-GP | 64.47015.6DL | R402H16 | 2005 | 4100 | 180 | YES |
| R332 | R402H16 | 0R2J-2-GP | 63.R0034.1DL | R402H16 | 10884.27 | 185.25 | 90 | NO |
| R333 | R402H16 | 47KR2F-GP | 64.47025.6DL | R402H16 | 755 | 5860 | 270 | NO |
| R334 | R402H16 | 47KR2F-GP | 64.47025.6DL | R402H16 | 755 | 5820 | 90 | NO |
| R335 | R402H16 | 10KR2F-2-GP | 64.10025.6DL | R402H16 | 2117.5 | 4957.4399999999996 | 270 | YES |
| R336 | R402H16 | 0R2J-2-GP | 63.R0034.1DL | R402H16 | 2115 | 4780 | 90 | NO |
| R337 | R402H16 | 49K9R2F-L-GP | 64.49925.6DL | R402H16 | 1800 | 5175 | 90 | YES |
| R338 | R603H22 | 2K74R3F-GP | 64.27415.55L | R603H22 | 2110 | 5300 | 270 | NO |
| R339 | R402H16 | 3K3R2F-2-GP | 64.33015.6DL | R402H16 | 3369 | 2220 | 270 | NO |
| R340 | R402H16 | 3K3R2F-2-GP | 64.33015.6DL | R402H16 | 825 | 5105 | 90 | YES |
| R341 | R402H16 | 3K3R2F-2-GP | 64.33015.6DL | R402H16 | 950.36 | 5302.66 | 90 | YES |
| R342 | R402H16 | 3K3R2F-2-GP | 64.33015.6DL | R402H16 | 694.2 | 5318.31 | 90 | NO |
| R343 | R402H16 | 3K3R2F-2-GP | 64.33015.6DL | R402H16 | 940 | 5265 | 90 | NO |
| R344 | R402H16 | 3K3R2F-2-GP | 64.33015.6DL | R402H16 | 825 | 5025 | 90 | YES |
| R345 | R402H16 | 3K3R2F-2-GP | 64.33015.6DL | R402H16 | 825 | 5145 | 90 | YES |
| R346 | R402H16 | 3K3R2F-2-GP | 64.33015.6DL | R402H16 | 694.2 | 5359.31 | 90 | NO |
| R347 | R402H16 | 3K3R2F-2-GP | 64.33015.6DL | R402H16 | 940 | 5225 | 90 | NO |
| R348 | R402H16 | 3K3R2F-2-GP | 64.33015.6DL | R402H16 | 812.69 | 5130.8999999999996 | 90 | NO |
| R349 | R402H16 | 3K3R2F-2-GP | 64.33015.6DL | R402H16 | 942.59 | 5135.67 | 90 | YES |
| R350 | R402H16 | 3K3R2F-2-GP | 64.33015.6DL | R402H16 | 941.2 | 5416.81 | 90 | YES |
| R351 | R402H16 | 3K3R2F-2-GP | 64.33015.6DL | R402H16 | 950.36 | 5262.66 | 90 | YES |
| R352 | R402H16 | 3K3R2F-2-GP | 64.33015.6DL | R402H16 | 821.44 | 5088.3100000000004 | 90 | NO |
| R353 | R402H16 | 3K3R2F-2-GP | 64.33015.6DL | R402H16 | 725 | 5145 | 270 | NO |
| R354 | R402H16 | 3K3R2F-2-GP | 64.33015.6DL | R402H16 | 940 | 5305 | 90 | NO |
| R355 | R402H16 | 3K3R2F-2-GP | 64.33015.6DL | R402H16 | 942.59 | 5175.67 | 90 | YES |
| R356 | R402H16 | 3K3R2F-2-GP | 64.33015.6DL | R402H16 | 936.87 | 4960.84 | 90 | YES |
| R357 | R402H16 | 3K3R2F-2-GP | 64.33015.6DL | R402H16 | 812.69 | 5170.8999999999996 | 90 | NO |
| R358 | R402H16 | 3K3R2F-2-GP | 64.33015.6DL | R402H16 | 940 | 5345 | 90 | NO |
| R359 | R402H16 | 3K3R2F-2-GP | 64.33015.6DL | R402H16 | 825 | 5185 | 90 | YES |
| R360 | R402H16 | 3K3R2F-2-GP | 64.33015.6DL | R402H16 | 936.87 | 5000.84 | 90 | YES |
| R361 | R402H16 | 3K3R2F-2-GP | 64.33015.6DL | R402H16 | 825 | 5065 | 90 | YES |
| R362 | R402H16 | 3K3R2F-2-GP | 64.33015.6DL | R402H16 | 941.2 | 5456.81 | 90 | YES |
| R363 | R402H16 | 3K3R2F-2-GP | 64.33015.6DL | R402H16 | 940 | 5185 | 90 | NO |
| R364 | R402H16 | 3K3R2F-2-GP | 64.33015.6DL | R402H16 | 936.87 | 5040.84 | 90 | YES |
| R365 | R402H16 | 3K3R2F-2-GP | 64.33015.6DL | R402H16 | 940 | 5060 | 90 | NO |
| R366 | R402H16 | 3K3R2F-2-GP | 64.33015.6DL | R402H16 | 940 | 5385 | 90 | NO |
| R367 | R402H16 | 3K3R2F-2-GP | 64.33015.6DL | R402H16 | 827 | 5293 | 270 | NO |
| R368 | R402H16 | 3K3R2F-2-GP | 64.33015.6DL | R402H16 | 821.44 | 5048.3100000000004 | 90 | NO |
| R369 | R402H16 | 3K3R2F-2-GP | 64.33015.6DL | R402H16 | 725 | 5105 | 270 | NO |
| R370 | R402H16 | 3K3R2F-2-GP | 64.33015.6DL | R402H16 | 941.2 | 5496.81 | 90 | YES |
| R371 | R402H16 | 0R2J-2-GP | 63.R0034.1DL | R402H16 | 10687.5 | 262.5 | 0 | YES |
| R372 | R402H16 | 0R2J-2-GP | 63.R0034.1DL | R402H16 | 1039.98 | 3425.5 | 0 | NO |
| R373 | R402H16 | 0R2J-2-GP | 63.R0034.1DL | R402H16 | 2115 | 5305 | 270 | YES |
| R374 | R603H22 | 0R3J-0-U-GP | 63.00000.00L | R603H22 | 674 | 2721 | 180 | YES |
| R375 | R402H16 | 0R2J-2-GP | 63.R0034.1DL | R402H16 | 1025 | 2909 | 90 | NO |
| R376 | R402H16 | 0R2J-2-GP | 63.R0034.1DL | R402H16 | 1025 | 2949 | 90 | NO |
| R377 | R402H16 | 0R2J-2-GP | 63.R0034.1DL | R402H16 | 12496.79 | 1315.95 | 0 | NO |
| R379 | R402H16 | 33R2J-2-GP | 63.33034.1DL | R402H16 | 973.07 | 2815.82 | 90 | NO |
| R382 | R402H16 | 0R2J-2-GP | 63.R0034.1DL | R402H16 | 1023 | 3286 | 90 | NO |
| R383 | R402H16 | 0R2J-2-GP | 63.R0034.1DL | R402H16 | 1022.4 | 3156.5 | 90 | NO |
| R384 | R402H16 | 0R2J-2-GP | 63.R0034.1DL | R402H16 | 1024 | 3241 | 90 | NO |
| R385 | R402H16 | 0R2J-2-GP | 63.R0034.1DL | R402H16 | 440 | 2768 | 270 | NO |
| R386 | R402H16 | 0R2J-2-GP | 63.R0034.1DL | R402H16 | 440 | 2809 | 270 | NO |
| R387 | R402H16 | 0R2J-2-GP | 63.R0034.1DL | R402H16 | 1021.9 | 3197.8 | 90 | NO |
| R388 | R402H16 | 0R2J-2-GP | 63.R0034.1DL | R402H16 | 10732.5 | 382.5 | 0 | YES |
| R389 | R402H16 | 0R2J-2-GP | 63.R0034.1DL | R402H16 | 10687.5 | 187.5 | 180 | YES |
| R390 | R402H16 | 4K99R2F-L-GP | 64.49915.6DL | R402H16 | 688.43 | 3547.37 | 270 | NO |
| R392 | R402H16 | 10KR2F-2-GP | 64.10025.6DL | R402H16 | 1025 | 3029 | 270 | NO |
| R393 | R402H16 | 10KR2F-2-GP | 64.10025.6DL | R402H16 | 1025 | 2989 | 270 | NO |
| R394 | R402H16 | 10KR2F-2-GP | 64.10025.6DL | R402H16 | 1085 | 2964 | 0 | NO |
| R395 | R402H16 | 10KR2F-2-GP | 64.10025.6DL | R402H16 | 1085 | 2889 | 180 | NO |
| R396 | R402H16 | 100KR2J-1-GP | 63.10434.1DL | R402H16 | 905 | 2739.4 | 90 | YES |
| R397 | R402H16 | 10KR2F-2-GP | 64.10025.6DL | R402H16 | 298.48 | 3108.72 | 90 | NO |
| R398 | R402H16 | 10KR2F-2-GP | 64.10025.6DL | R402H16 | 299.12 | 3066.74 | 90 | NO |
| R399 | R402H16 | 10KR2F-2-GP | 64.10025.6DL | R402H16 | 433 | 3214 | 90 | NO |
| R400 | R402H16 | 10KR2F-2-GP | 64.10025.6DL | R402H16 | 374 | 3941 | 270 | NO |
| R401 | R402H16 | 10KR2F-2-GP | 64.10025.6DL | R402H16 | 628 | 3289 | 0 | NO |
| R402 | R402H16 | 3K3R2F-2-GP | 64.33015.6DL | R402H16 | 916 | 3424 | 0 | NO |
| R403 | R402H16 | 3K3R2F-2-GP | 64.33015.6DL | R402H16 | 583 | 3292 | 0 | NO |
| R404 | R402H16 | 3K3R2F-2-GP | 64.33015.6DL | R402H16 | 1065 | 2789 | 180 | NO |
| R405 | R402H16 | 3K3R2F-2-GP | 64.33015.6DL | R402H16 | 956.7 | 3425.11 | 0 | NO |
| R406 | R402H16 | 3K3R2F-2-GP | 64.33015.6DL | R402H16 | 995 | 2763 | 270 | NO |
| R407 | R402H16 | 10KR2F-2-GP | 64.10025.6DL | R402H16 | 652.69000000000005 | 5022.2 | 90 | NO |
| R408 | R402H16 | 4K7R2F-GP | 64.47015.6DL | R402H16 | 1823 | 4096 | 180 | YES |
| R409 | R402H16 | 0R2J-2-GP | 63.R0034.1DL | R402H16 | 1707.84 | 1816.86 | 270 | NO |
| R410 | R402H16 | 0R2J-2-GP | 63.R0034.1DL | R402H16 | 1707.84 | 1866.86 | 270 | NO |
| R411 | R402H16 | 4K7R2F-GP | 64.47015.6DL | R402H16 | 1978 | 4455 | 0 | YES |
| R412 | R402H16 | 0R2J-2-GP | 63.R0034.1DL | R402H16 | 8622 | 39 | 90 | NO |
| R413 | R402H16 | 0R2J-2-GP | 63.R0034.1DL | R402H16 | 12537.19 | 1315.95 | 0 | NO |
| R414 | R402H16 | 10KR2F-2-GP | 64.10025.6DL | R402H16 | 2243.6999999999998 | 5680.2 | 270 | NO |
| R415 | R402H16 | 0R2J-2-GP | 63.R0034.1DL | R402H16 | 2243.7199999999998 | 5639.94 | 90 | NO |
| R416 | R402H16 | 0R2J-2-GP | 63.R0034.1DL | R402H16 | 998.87 | 3425.75 | 0 | NO |
| R417 | R402H16 | 10KR2F-2-GP | 64.10025.6DL | R402H16 | 1449.98 | 4203.0600000000004 | 270 | NO |
| R418 | R402H16 | 10KR2F-2-GP | 64.10025.6DL | R402H16 | 2262 | 5741.62 | 0 | NO |
| R419 | R402H16 | 10KR2F-2-GP | 64.10025.6DL | R402H16 | 803 | 2609 | 0 | NO |
| R420 | R402H16 | 10KR2F-2-GP | 64.10025.6DL | R402H16 | 2510 | 4999 | 0 | YES |
| R421 | R402H16 | 4K7R2F-GP | 64.47015.6DL | R402H16 | 2331.4299999999998 | 4899.29 | 90 | YES |
| R422 | R402H16 | 4K7R2F-GP | 64.47015.6DL | R402H16 | 1896 | 4454 | 0 | YES |
| R423 | R402H16 | 2K2R2J-2-GP | 63.22234.1DL | R402H16 | 3374.1 | 2941.6 | 180 | NO |
| R424 | R402H16 | 0R2J-2-GP | 63.R0034.1DL | R402H16 | 11360 | 2345 | 270 | NO |
| R425 | R603H22 | 0R3J-0-U-GP | 63.00000.00L | R603H22 | 721 | 2721 | 180 | YES |
| R426 | R402H16 | 10KR2F-2-GP | 64.10025.6DL | R402H16 | 2825 | 4935 | 180 | NO |
| R427 | R402H16 | 2KR2F-3-GP | 64.20015.6DL | R402H16 | 4822 | 3933 | 270 | NO |
| R428 | R402H16 | 10KR2F-2-GP | 64.10025.6DL | R402H16 | 4937 | 3743 | 180 | NO |
| R429 | R402H16 | 2KR2F-3-GP | 64.20015.6DL | R402H16 | 4747 | 3933 | 90 | NO |
| R430 | R402H16 | 10KR2F-2-GP | 64.10025.6DL | R402H16 | 4627 | 3823 | 180 | NO |
| R431 | R402H16 | 0R2J-2-GP | 63.R0034.1DL | R402H16 | 4802 | 3787 | 180 | YES |
| R432 | R402H16 | 0R2J-2-GP | 63.R0034.1DL | R402H16 | 4762 | 3787 | 180 | YES |
| R433 | R402H16 | 4K7R2F-GP | 64.47015.6DL | R402H16 | 1936 | 4454 | 0 | YES |
| R434 | R402H16 | 3K3R2F-2-GP | 64.33015.6DL | R402H16 | 2290 | 5275 | 180 | YES |
| R435 | R402H16 | 0R2J-2-GP | 63.R0034.1DL | R402H16 | 8640 | 80 | 90 | NO |
| R436 | R402H16 | 4K7R2F-GP | 64.47015.6DL | R402H16 | 2161 | 4482 | 90 | YES |
| R437 | R402H16 | 4K7R2F-GP | 64.47015.6DL | R402H16 | 2085.2600000000002 | 4481.6499999999996 | 270 | YES |
| R438 | R402H16 | 4K7R2F-GP | 64.47015.6DL | R402H16 | 2592 | 4433 | 90 | NO |
| R439 | R402H16 | 4K7R2F-GP | 64.47015.6DL | R402H16 | 2517 | 4433 | 270 | NO |
| R440 | R402H16 | 4K7R2F-GP | 64.47015.6DL | R402H16 | 2152 | 4460 | 90 | NO |
| R441 | R402H16 | 4K7R2F-GP | 64.47015.6DL | R402H16 | 2077 | 4460 | 270 | NO |
| R442 | R402H16 | 0R2J-2-GP | 63.R0034.1DL | R402H16 | 1501.5 | 4509.8999999999996 | 180 | YES |
| R443 | R402H16 | 0R2J-2-GP | 63.R0034.1DL | R402H16 | 1101 | 7279 | 270 | YES |
| R444 | R402H16 | 0R2J-2-GP | 63.R0034.1DL | R402H16 | 1556.8 | 4509.3 | 180 | YES |
| R446 | R603H22 | 0R3J-0-U-GP | 63.00000.00L | R603H22 | 1143.6400000000001 | 1292.99 | 0 | NO |
| R447 | R402H16 | 100KR2F-L1-GP | 64.10035.6DL | R402H16 | 5329.21 | 2928.17 | 180 | NO |
| R448 | R402H16 | 0R2J-2-GP | 63.R0034.1DL | R402H16 | 1101 | 7319 | 270 | YES |
| R449 | R402H16 | 0R2J-2-GP | 63.R0034.1DL | R402H16 | 1090 | 5615 | 270 | NO |
| R450 | R402H16 | 0R2J-2-GP | 63.R0034.1DL | R402H16 | 1090 | 5655 | 270 | NO |
| R451 | R402H16 | 0R2J-2-GP | 63.R0034.1DL | R402H16 | 2115 | 5020 | 90 | NO |
| R452 | R402H16 | 0R2J-2-GP | 63.R0034.1DL | R402H16 | 2115 | 5060 | 90 | NO |
| R453 | R402H16 | 10KR2F-2-GP | 64.10025.6DL | R402H16 | 2824.78 | 7704.31 | 0 | NO |
| R454 | R402H16 | 0R2J-2-GP | 63.R0034.1DL | R402H16 | 8675 | 220 | 180 | NO |
| R456 | R402H16 | 4K7R2F-GP | 64.47015.6DL | R402H16 | 2331 | 5060 | 90 | YES |
| R457 | R402H16 | 4K7R2F-GP | 64.47015.6DL | R402H16 | 2331 | 5020 | 90 | YES |
| R458 | R402H16 | 100KR2F-L1-GP | 64.10035.6DL | R402H16 | 5228.99 | 2352.37 | 180 | NO |
| R459 | R402H16 | 10KR2F-2-GP | 64.10025.6DL | R402H16 | 1002 | 2754.6 | 90 | YES |
| R460 | R402H16 | 0R2J-2-GP | 63.R0034.1DL | R402H16 | 2115 | 4650 | 270 | NO |
| R461 | R402H16 | 0R2J-2-GP | 63.R0034.1DL | R402H16 | 2115 | 4690 | 270 | NO |
| R462 | R402H16 | 0R2J-2-GP | 63.R0034.1DL | R402H16 | 1936.5 | 4568.22 | 180 | YES |
| R464 | R402H16 | 0R2J-2-GP | 63.R0034.1DL | R402H16 | 1461.5 | 4509.8999999999996 | 180 | YES |
| R465 | R402H16 | 0R2J-2-GP | 63.R0034.1DL | R402H16 | 1896.5 | 4568.22 | 180 | YES |
| R466 | R402H16 | 0R2J-2-GP | 63.R0034.1DL | R402H16 | 2127.23 | 4877.04 | 270 | YES |
| R467 | R402H16 | 0R2J-2-GP | 63.R0034.1DL | R402H16 | 2127.23 | 4837.04 | 270 | YES |
| R468 | R402H16 | 2KR2F-3-GP | 64.20015.6DL | R402H16 | 1069 | 7263 | 180 | NO |
| R469 | R402H16 | 0R2J-2-GP | 63.R0034.1DL | R402H16 | 2029 | 5028 | 90 | YES |
| R470 | R402H16 | 0R2J-2-GP | 63.R0034.1DL | R402H16 | 2017 | 4563.3500000000004 | 0 | YES |
| R471 | R402H16 | 0R2J-2-GP | 63.R0034.1DL | R402H16 | 1977 | 4563.3500000000004 | 0 | YES |
| R472 | R402H16 | 2K2R2J-2-GP | 63.22234.1DL | R402H16 | 2331.4299999999998 | 4738.29 | 90 | YES |
| R473 | R402H16 | 0R2J-2-GP | 63.R0034.1DL | R402H16 | 1728 | 4595 | 0 | NO |
| R474 | R603H22 | 0R3J-0-U-GP | 63.00000.00L | R603H22 | 681 | 2623 | 180 | NO |
| R475 | R402H16 | 4K7R2F-GP | 64.47015.6DL | R402H16 | 2305.7199999999998 | 4606.13 | 0 | YES |
| R476 | R402H16 | 10KR2F-2-GP | 64.10025.6DL | R402H16 | 534.22 | 3561.14 | 180 | NO |
| R477 | R402H16 | 4K7R2F-GP | 64.47015.6DL | R402H16 | 3083 | 3343 | 180 | NO |
| R478 | R402H16 | 2MR2F-GP | 64.20045.6DL | R402H16 | 2632.29 | 3341.4 | 90 | NO |
| R479 | R2010H28 | 51R2010F-GP | 64.51R05.F9L | R2010H28 | 2822.29 | 3546.4 | 270 | NO |
| R480 | R402H16 | 10KR2F-2-GP | 64.10025.6DL | R402H16 | 2501 | 3397 | 90 | NO |
| R481 | R603H22 | 200R3F-GP | 64.20005.55L | R603H22 | 3078.39 | 3405.01 | 270 | NO |
| R482 | R402H16 | 0R2J-2-GP | 63.R0034.1DL | R402H16 | 2667.29 | 3476.4 | 0 | NO |
| R483 | R402H16 | 0R2J-2-GP | 63.R0034.1DL | R402H16 | 2667.29 | 3556.4 | 180 | NO |
| R484 | R402H16 | 1KR2F-3-GP | 64.10015.6DL | R402H16 | 3153 | 3390 | 0 | NO |
| R485 | R402H16 | 1KR2F-3-GP | 64.10015.6DL | R402H16 | 2996.39 | 3344.01 | 0 | NO |
| R486 | R402H16 | 10KR2F-2-GP | 64.10025.6DL | R402H16 | 1307 | 7452 | 270 | NO |
| R487 | R402H16 | 0R2J-2-GP | 63.R0034.1DL | R402H16 | 2534 | 4492 | 0 | NO |
| R488 | R402H16 | 0R2J-2-GP | 63.R0034.1DL | R402H16 | 2575 | 4492.38 | 0 | NO |
| R489 | R402H16 | 4K7R2F-GP | 64.47015.6DL | R402H16 | 660 | 6000 | 0 | NO |
| R490 | R402H16 | 0R2J-2-GP | 63.R0034.1DL | R402H16 | 2143 | 4558 | 0 | YES |
| R491 | R402H16 | 0R2J-2-GP | 63.R0034.1DL | R402H16 | 660 | 5925 | 180 | NO |
| R492 | R402H16 | 2K2R2J-2-GP | 63.22234.1DL | R402H16 | 2331.4299999999998 | 4778.29 | 90 | YES |
| R493 | R402H16 | 4K7R2F-GP | 64.47015.6DL | R402H16 | 880 | 6086 | 0 | NO |
| R494 | R402H16 | 0R2J-2-GP | 63.R0034.1DL | R402H16 | 9570.81 | 646.24 | 270 | NO |
| R495 | R402H16 | 0R2J-2-GP | 63.R0034.1DL | R402H16 | 1002 | 3866 | 0 | NO |
| R496 | R402H16 | 0R2J-2-GP | 63.R0034.1DL | R402H16 | 7348 | 140 | 90 | NO |
| R497 | R402H16 | 33K2R2F-GP | 64.33225.6DL | R402H16 | 1864.18 | 1980.56 | 180 | NO |
| R498 | R402H16 | 33K2R2F-GP | 64.33225.6DL | R402H16 | 1960.18 | 1980.56 | 0 | NO |
| R499 | R402H16 | 3K3R2F-2-GP | 64.33015.6DL | R402H16 | 1910.18 | 1980.56 | 0 | NO |
| R500 | R402H16 | 3K3R2F-2-GP | 64.33015.6DL | R402H16 | 2003 | 1981 | 180 | NO |
| R501 | R402H16 | 3K3R2F-2-GP | 64.33015.6DL | R402H16 | 2046 | 2510 | 90 | NO |
| R502 | R402H16 | 2KR2F-3-GP | 64.20015.6DL | R402H16 | 1069 | 7338 | 0 | NO |
| R503 | R402H16 | 10KR2F-2-GP | 64.10025.6DL | R402H16 | 1179 | 7143 | 270 | NO |
| R504 | R402H16 | 0R2J-2-GP | 63.R0034.1DL | R402H16 | 975 | 6335 | 0 | NO |
| R505 | R402H16 | 4K7R2F-GP | 64.47015.6DL | R402H16 | 885 | 6420 | 270 | NO |
| R506 | R402H16 | 0R2J-2-GP | 63.R0034.1DL | R402H16 | 1370 | 4595 | 180 | YES |
| R507 | R402H16 | 0R2J-2-GP | 63.R0034.1DL | R402H16 | 1352.5 | 4419.8999999999996 | 180 | NO |
| R508 | R402H16 | 3K3R2F-2-GP | 64.33015.6DL | R402H16 | 1957 | 2511 | 270 | NO |
| R510 | R402H16 | 0R2J-2-GP | 63.R0034.1DL | R402H16 | 885 | 6460 | 270 | NO |
| R511 | R603H22 | 150R3J-L-GP | 63.15133.15L | R603H22 | 273 | 2202 | 0 | NO |
| R512 | R402H16 | 0R2J-2-GP | 63.R0034.1DL | R402H16 | 924 | 2056 | 180 | NO |
| R513 | R402H16 | 10KR2F-2-GP | 64.10025.6DL | R402H16 | 12735 | 3920 | 0 | NO |
| R514 | R603H22 | 150R3J-L-GP | 63.15133.15L | R603H22 | 1082.24 | 1613.87 | 0 | NO |
| R515 | R402H16 | 0R2J-2-GP | 63.R0034.1DL | R402H16 | 778 | 2111 | 180 | NO |
| R516 | R402H16 | 10KR2F-2-GP | 64.10025.6DL | R402H16 | 2784.06 | 7213.98 | 180 | NO |
| R517 | R402H16 | 10KR2F-2-GP | 64.10025.6DL | R402H16 | 2744.06 | 7213.98 | 180 | NO |
| R518 | R402H16 | 10KR2F-2-GP | 64.10025.6DL | R402H16 | 2784.06 | 7213.98 | 180 | YES |
| R519 | R402H16 | 10KR2F-2-GP | 64.10025.6DL | R402H16 | 2823.78 | 7704.31 | 0 | YES |
| R520 | R402H16 | 4K7R2F-GP | 64.47015.6DL | R402H16 | 2305.71 | 4680.17 | 180 | YES |
| R521 | R402H16 | 10KR2F-2-GP | 64.10025.6DL | R402H16 | 2744.06 | 7213.98 | 180 | YES |
| R522 | R402H16 | 4K7R2F-GP | 64.47015.6DL | R402H16 | 577 | 4975 | 180 | YES |
| R523 | R402H16 | 0R2J-2-GP | 63.R0034.1DL | R402H16 | 825 | 5305 | 270 | YES |
| R524 | R402H16 | 4K7R2F-GP | 64.47015.6DL | R402H16 | 536 | 4975 | 180 | YES |
| R525 | R402H16 | 10KR2F-2-GP | 64.10025.6DL | R402H16 | 4919.0600000000004 | 7733.98 | 180 | YES |
| R526 | R402H16 | 10KR2F-2-GP | 64.10025.6DL | R402H16 | 12665 | 3405 | 180 | NO |
| R527 | R402H16 | 10KR2F-2-GP | 64.10025.6DL | R402H16 | 12585 | 3405 | 180 | NO |
| R528 | R402H16 | 33R2J-2-GP | 63.33034.1DL | R402H16 | 270 | 3610 | 180 | NO |
| R529 | R402H16 | 1KR2F-3-GP | 64.10015.6DL | R402H16 | 7365 | 260 | 0 | NO |
| R530 | R402H16 | 0R2J-2-GP | 63.R0034.1DL | R402H16 | 2029 | 5068 | 90 | YES |
| R531 | R402H16 | 0R2J-2-GP | 63.R0034.1DL | R402H16 | 2103 | 4558 | 0 | YES |
| R532 | R402H16 | 1KR2F-3-GP | 64.10015.6DL | R402H16 | 7347.63 | 318.82 | 270 | NO |
| R533 | R402H16 | 0R2J-2-GP | 63.R0034.1DL | R402H16 | 2029 | 5109 | 90 | YES |
| R534 | R402H16 | 0R2J-2-GP | 63.R0034.1DL | R402H16 | 2029 | 5149 | 90 | YES |
| R535 | R402H16 | 10KR2F-2-GP | 64.10025.6DL | R402H16 | 4958.78 | 8224.31 | 0 | YES |
| R536 | R402H16 | 10KR2F-2-GP | 64.10025.6DL | R402H16 | 4879.0600000000004 | 7733.98 | 180 | YES |
| R537 | R402H16 | 0R2J-2-GP | 63.R0034.1DL | R402H16 | 1775 | 4595 | 0 | YES |
| R538 | R402H16 | 0R2J-2-GP | 63.R0034.1DL | R402H16 | 823.22 | 5627.89 | 270 | YES |
| R539 | R402H16 | 0R2J-2-GP | 63.R0034.1DL | R402H16 | 1088 | 2122 | 90 | NO |
| R540 | R402H16 | 0R2J-2-GP | 63.R0034.1DL | R402H16 | 1080.5 | 1334.6 | 180 | NO |
| R541 | R402H16 | 0R2J-2-GP | 63.R0034.1DL | R402H16 | 953.49 | 4772.41 | 90 | NO |
| R542 | R402H16 | 0R2J-2-GP | 63.R0034.1DL | R402H16 | 2094 | 4518 | 0 | NO |
| R543 | R1210H24 | 330R1210J-GP | 63.33137.1BL | R1210H24 | 7891 | 11 | 270 | NO |
| R544 | R402H16 | 1KR2F-3-GP | 64.10015.6DL | R402H16 | 7543 | 538 | 270 | NO |
| R545 | R603H22 | 0R3J-0-U-GP | 63.00000.00L | R603H22 | 1818.38 | 1292.1099999999999 | 0 | NO |
| R546 | R402H16 | 10KR2F-2-GP | 64.10025.6DL | R402H16 | 1808.39 | 4507.47 | 90 | NO |
| R547 | R402H16 | 10KR2F-2-GP | 64.10025.6DL | R402H16 | 4919.0600000000004 | 7733.98 | 180 | NO |
| R548 | R402H16 | 10KR2F-2-GP | 64.10025.6DL | R402H16 | 4879.0600000000004 | 7733.98 | 180 | NO |
| R549 | R402H16 | 10KR2F-2-GP | 64.10025.6DL | R402H16 | 4959.78 | 8224.31 | 0 | NO |
| R550 | R402H16 | 10KR2F-2-GP | 64.10025.6DL | R402H16 | 8614.06 | 7503.98 | 180 | NO |
| R551 | R402H16 | 10KR2F-2-GP | 64.10025.6DL | R402H16 | 8653.7800000000007 | 7994.31 | 0 | YES |
| R552 | R402H16 | 10KR2F-2-GP | 64.10025.6DL | R402H16 | 8574.06 | 7503.98 | 180 | NO |
| R553 | R402H16 | 10KR2F-2-GP | 64.10025.6DL | R402H16 | 8609.06 | 7503.98 | 180 | YES |
| R554 | R402H16 | 0R2J-2-GP | 63.R0034.1DL | R402H16 | 950 | 4764 | 270 | YES |
| R555 | R402H16 | 10KR2F-2-GP | 64.10025.6DL | R402H16 | 8569.06 | 7503.98 | 180 | YES |
| R556 | R402H16 | 10KR2F-2-GP | 64.10025.6DL | R402H16 | 1464.31 | 4517.78 | 180 | NO |
| R557 | R402H16 | 10KR2F-2-GP | 64.10025.6DL | R402H16 | 8654.7800000000007 | 7994.31 | 0 | NO |
| R558 | R402H16 | 0R2J-2-GP | 63.R0034.1DL | R402H16 | 6795 | 2120 | 270 | NO |
| R559 | R402H16 | 10KR2F-2-GP | 64.10025.6DL | R402H16 | 12705 | 3405 | 180 | NO |
| R560 | R402H16 | 0R2J-2-GP | 63.R0034.1DL | R402H16 | 884 | 2056 | 180 | NO |
| R561 | R402H16 | 10KR2F-2-GP | 64.10025.6DL | R402H16 | 1808.54 | 4466.72 | 270 | NO |
| R562 | R402H16 | 0R2J-2-GP | 63.R0034.1DL | R402H16 | 1841.16 | 4603.1000000000004 | 0 | NO |
| R563 | R402H16 | 10KR2F-2-GP | 64.10025.6DL | R402H16 | 13102 | 7279 | 0 | NO |
| R564 | R402H16 | 0R2J-2-GP | 63.R0034.1DL | R402H16 | 1288.92 | 4706.8 | 90 | YES |
| R565 | R402H16 | 0R2J-2-GP | 63.R0034.1DL | R402H16 | 721.08 | 5065.5200000000004 | 270 | YES |
| R566 | R402H16 | 4K7R2F-GP | 64.47015.6DL | R402H16 | 7692 | 740 | 90 | NO |
| R567 | R402H16 | 4K7R2F-GP | 64.47015.6DL | R402H16 | 2842 | 4728 | 180 | NO |
| R568 | R402H16 | 10KR2F-2-GP | 64.10025.6DL | R402H16 | 12625 | 3405 | 180 | NO |
| R569 | R402H16 | 4K7R2F-GP | 64.47015.6DL | R402H16 | 2249 | 1111 | 0 | NO |
| R570 | R402H16 | 10KR2F-2-GP | 64.10025.6DL | R402H16 | 2246 | 1218 | 0 | NO |
| R571 | R402H16 | 10KR2F-2-GP | 64.10025.6DL | R402H16 | 2368 | 1002 | 0 | YES |
| R572 | R402H16 | 4K7R2F-GP | 64.47015.6DL | R402H16 | 7594.5 | 759 | 270 | NO |
| R573 | R402H16 | 10KR2F-2-GP | 64.10025.6DL | R402H16 | 13101 | 7279 | 0 | YES |
| R574 | R402H16 | 10KR2F-2-GP | 64.10025.6DL | R402H16 | 13061.28 | 6788.67 | 180 | NO |
| R575 | R402H16 | 10KR2F-2-GP | 64.10025.6DL | R402H16 | 13021.28 | 6788.67 | 180 | NO |
| R576 | R402H16 | 10KR2F-2-GP | 64.10025.6DL | R402H16 | 13061.28 | 6788.67 | 180 | YES |
| R577 | R402H16 | 10KR2F-2-GP | 64.10025.6DL | R402H16 | 13021.28 | 6788.67 | 180 | YES |
| R578 | R402H16 | 4K7R2F-GP | 64.47015.6DL | R402H16 | 2415 | 4900 | 270 | YES |
| R579 | R402H16 | 4K7R2F-GP | 64.47015.6DL | R402H16 | 2415 | 4860 | 270 | YES |
| R580 | R402H16 | 4K7R2F-GP | 64.47015.6DL | R402H16 | 2215 | 4690 | 90 | NO |
| R581 | R402H16 | 4K7R2F-GP | 64.47015.6DL | R402H16 | 2215 | 4650 | 90 | NO |
| R582 | R402H16 | 0R2J-2-GP | 63.R0034.1DL | R402H16 | 738 | 2111 | 180 | NO |
| R583 | R402H16 | 4K7R2F-GP | 64.47015.6DL | R402H16 | 8085 | 824 | 90 | NO |
| R584 | R402H16 | 0R2J-2-GP | 63.R0034.1DL | R402H16 | 2245 | 5585 | 270 | YES |
| R585 | R402H16 | 4K7R2F-GP | 64.47015.6DL | R402H16 | 9020 | 3630 | 90 | NO |
| R586 | R402H16 | 4K7R2F-GP | 64.47015.6DL | R402H16 | 9020 | 3500 | 270 | NO |
| R587 | R402H16 | 0R2J-2-GP | 63.R0034.1DL | R402H16 | 8910 | 3076 | 180 | NO |
| R588 | R402H16 | 0R2J-2-GP | 63.R0034.1DL | R402H16 | 8950 | 3076 | 180 | NO |
| R589 | R402H16 | 4K7R2F-GP | 64.47015.6DL | R402H16 | 1915 | 5850 | 180 | NO |
| R590 | R402H16 | 4K7R2F-GP | 64.47015.6DL | R402H16 | 1955 | 5850 | 0 | NO |
| R591 | R402H16 | 4K7R2F-GP | 64.47015.6DL | R402H16 | 9020 | 3416 | 90 | NO |
| R592 | R402H16 | 4K7R2F-GP | 64.47015.6DL | R402H16 | 9020 | 3585 | 270 | NO |
| R593 | R402H16 | 10KR2F-2-GP | 64.10025.6DL | R402H16 | 12695 | 3920 | 0 | NO |
| R594 | R402H16 | 0R2J-2-GP | 63.R0034.1DL | R402H16 | 570 | 2062 | 180 | NO |
| R595 | R402H16 | 0R2J-2-GP | 63.R0034.1DL | R402H16 | 416.5 | 2110 | 180 | NO |
| R596 | R402H16 | 0R2J-2-GP | 63.R0034.1DL | R402H16 | 530 | 2062 | 180 | NO |
| R597 | R402H16 | 0R2J-2-GP | 63.R0034.1DL | R402H16 | 376.5 | 2110 | 180 | NO |
| R598 | R402H16 | 4K7R2F-GP | 64.47015.6DL | R402H16 | 2415 | 4780 | 270 | YES |
| R599 | R402H16 | 4K7R2F-GP | 64.47015.6DL | R402H16 | 2415 | 4820 | 270 | YES |
| R600 | R402H16 | 4K7R2F-GP | 64.47015.6DL | R402H16 | 532 | 4684 | 0 | NO |
| R601 | R402H16 | 4K7R2F-GP | 64.47015.6DL | R402H16 | 532 | 4760 | 180 | NO |
| R602 | R402H16 | 10KR2F-2-GP | 64.10025.6DL | R402H16 | 1558 | 4022 | 90 | NO |
| R603 | R402H16 | 0R2J-2-GP | 63.R0034.1DL | R402H16 | 924 | 2170 | 180 | NO |
| R605 | R402H16 | 10KR2F-2-GP | 64.10025.6DL | R402H16 | 1162.3499999999999 | 4495.3500000000004 | 180 | NO |
| R606 | R402H16 | 22R2F-1-GP | 64.22R05.6DL | R402H16 | 825 | 5385 | 90 | YES |
| R607 | R402H16 | 0R2J-2-GP | 63.R0034.1DL | R402H16 | 825 | 5545 | 270 | NO |
| R608 | R402H16 | 0R2J-2-GP | 63.R0034.1DL | R402H16 | 6909 | 2122 | 270 | NO |
| R609 | R402H16 | 0R2J-2-GP | 63.R0034.1DL | R402H16 | 11220 | 2350 | 270 | NO |
| R610 | R402H16 | 4K7R2F-GP | 64.47015.6DL | R402H16 | 13170 | 2745 | 270 | NO |
| R611 | R402H16 | 0R2J-2-GP | 63.R0034.1DL | R402H16 | 778 | 2226 | 180 | NO |
| R612 | R402H16 | 0R2J-2-GP | 63.R0034.1DL | R402H16 | 884 | 2170 | 180 | NO |
| R613 | R402H16 | 0R2J-2-GP | 63.R0034.1DL | R402H16 | 738 | 2226 | 180 | NO |
| R614 | R402H16 | 0R2J-2-GP | 63.R0034.1DL | R402H16 | 824 | 5504 | 270 | NO |
| R615 | R402H16 | 100KR2F-L1-GP | 64.10035.6DL | R402H16 | 5416.81 | 2927.76 | 0 | NO |
| R616 | R402H16 | 100KR2F-L1-GP | 64.10035.6DL | R402H16 | 5175.99 | 2352.37 | 180 | NO |
| R617 | R402H16 | 27KR2F-L-GP | 64.27025.6DL | R402H16 | 967 | 6819 | 270 | NO |
| R618 | R402H16 | 47KR2F-GP | 64.47025.6DL | R402H16 | 2073.69 | 1494.84 | 0 | NO |
| R619 | R402H16 | 0R2J-2-GP | 63.R0034.1DL | R402H16 | 4808.8100000000004 | 1383.14 | 180 | NO |
| R620 | R402H16 | 0R2J-2-GP | 63.R0034.1DL | R402H16 | 1405 | 4509.8999999999996 | 180 | YES |
| R621 | R402H16 | 0R2J-2-GP | 63.R0034.1DL | R402H16 | 4716.6000000000004 | 1430.08 | 90 | NO |
| R622 | R402H16 | 0R2J-2-GP | 63.R0034.1DL | R402H16 | 4989.03 | 1668.92 | 180 | NO |
| R623 | R402H16 | 0R2J-2-GP | 63.R0034.1DL | R402H16 | 5077 | 1698 | 180 | NO |
| R624 | R402H16 | 0R2J-2-GP | 63.R0034.1DL | R402H16 | 13125.26 | 1511.99 | 90 | NO |
| R625 | R402H16 | 0R2J-2-GP | 63.R0034.1DL | R402H16 | 13118.1 | 1453.1 | 90 | NO |
| R626 | R402H16 | 0R2J-2-GP | 63.R0034.1DL | R402H16 | 13351 | 1436.7 | 0 | NO |
| R627 | R402H16 | 0R2J-2-GP | 63.R0034.1DL | R402H16 | 13350.71 | 1361.11 | 180 | NO |
| R628 | R1206H26 | 56R6J-GP | 63.56032.11L | R1206H26 | 2233 | 1606 | 270 | NO |
| R629 | R402H16 | 10KR2F-2-GP | 64.10025.6DL | R402H16 | 2094.4899999999998 | 1435.87 | 90 | NO |
| R630 | R402H16 | 0R2J-2-GP | 63.R0034.1DL | R402H16 | 1420 | 4550 | 0 | NO |
| R631 | R402H16 | 47KR2F-GP | 64.47025.6DL | R402H16 | 1513.14 | 3222.77 | 270 | NO |
| R632 | R402H16 | 0R2J-2-GP | 63.R0034.1DL | R402H16 | 7370.8 | 1094.0999999999999 | 90 | NO |
| R633 | R402H16 | 0R2J-2-GP | 63.R0034.1DL | R402H16 | 5059.42 | 1305.47 | 90 | NO |
| R634 | R402H16 | 0R2J-2-GP | 63.R0034.1DL | R402H16 | 5697 | 1317.3 | 180 | NO |
| R635 | R603H22 | 0R3J-0-U-GP | 63.00000.00L | R603H22 | 1710.94 | 2409.61 | 180 | NO |
| R636 | R402H16 | 0R2J-2-GP | 63.R0034.1DL | R402H16 | 825 | 5425 | 270 | YES |
| R637 | R402H16 | 0R2J-2-GP | 63.R0034.1DL | R402H16 | 6177.11 | 1315.81 | 180 | NO |
| R638 | R402H16 | 22R2F-1-GP | 64.22R05.6DL | R402H16 | 825 | 5345 | 90 | YES |
| R639 | R402H16 | 0R2J-2-GP | 63.R0034.1DL | R402H16 | 825 | 5225 | 270 | YES |
| R640 | R402H16 | 0R2J-2-GP | 63.R0034.1DL | R402H16 | 825 | 5423 | 270 | NO |
| R641 | R402H16 | 4K7R2F-GP | 64.47015.6DL | R402H16 | 10504.86 | 112.08 | 90 | NO |
| R642 | R402H16 | 0R2J-2-GP | 63.R0034.1DL | R402H16 | 2135 | 4518 | 0 | NO |
| R643 | R402H16 | 0R2J-2-GP | 63.R0034.1DL | R402H16 | 11505 | 2345 | 270 | NO |
| R644 | R402H16 | 4K7R2F-GP | 64.47015.6DL | R402H16 | 4558 | 1047 | 180 | NO |
| R645 | R402H16 | 0R2J-2-GP | 63.R0034.1DL | R402H16 | 825 | 5463 | 270 | NO |
| R646 | R402H16 | 10KR2F-2-GP | 64.10025.6DL | R402H16 | 1036.17 | 3345.15 | 0 | NO |
| R647 | R402H16 | 0R2J-2-GP | 63.R0034.1DL | R402H16 | 825 | 5505 | 270 | YES |
| R648 | R402H16 | 27KR2F-L-GP | 64.27025.6DL | R402H16 | 892 | 6819 | 90 | NO |
| R649 | R402H16 | 0R2J-2-GP | 63.R0034.1DL | R402H16 | 2060.7600000000002 | 2031 | 0 | YES |
| R650 | R402H16 | 100KR2F-L1-GP | 64.10035.6DL | R402H16 | 5241.7700000000004 | 2929.4 | 180 | NO |
| R651 | R402H16 | 100KR2F-L1-GP | 64.10035.6DL | R402H16 | 5312.32 | 2352.2399999999998 | 180 | NO |
| R652 | R402H16 | 100KR2F-L1-GP | 64.10035.6DL | R402H16 | 9065 | 410 | 90 | NO |
| R653 | R402H16 | 100KR2F-L1-GP | 64.10035.6DL | R402H16 | 9065 | 370 | 270 | NO |
| R654 | R402H16 | 100KR2F-L1-GP | 64.10035.6DL | R402H16 | 8640 | 485 | 270 | NO |
| R655 | R402H16 | 4K7R2F-GP | 64.47015.6DL | R402H16 | 5241 | 3405 | 270 | NO |
| R656 | R402H16 | 4K7R2F-GP | 64.47015.6DL | R402H16 | 1516 | 4080 | 0 | NO |
| R657 | R402H16 | 100KR2F-L1-GP | 64.10035.6DL | R402H16 | 8635 | 400 | 270 | NO |
| R658 | R402H16 | 4K7R2F-GP | 64.47015.6DL | R402H16 | 1557 | 4080 | 180 | NO |
| R659 | R402H16 | 0R2J-2-GP | 63.R0034.1DL | R402H16 | 825 | 5465 | 270 | YES |
| R660 | R402H16 | 100KR2F-L1-GP | 64.10035.6DL | R402H16 | 8635 | 320 | 270 | NO |
| R661 | R402H16 | 100KR2F-L1-GP | 64.10035.6DL | R402H16 | 8638.33 | 440.34 | 90 | NO |
| R662 | R402H16 | 100KR2F-L1-GP | 64.10035.6DL | R402H16 | 8635 | 360 | 90 | NO |
| R663 | R402H16 | 100KR2F-L1-GP | 64.10035.6DL | R402H16 | 8635 | 280 | 90 | NO |
| R664 | R402H16 | 27KR2F-L-GP | 64.27025.6DL | R402H16 | 572 | 6847 | 180 | NO |
| R665 | R402H16 | 4K7R2F-GP | 64.47015.6DL | R402H16 | 8544 | 160 | 0 | NO |
| R666 | R402H16 | 0R2J-2-GP | 63.R0034.1DL | R402H16 | 7371 | 1140.2 | 90 | NO |
| R667 | R402H16 | 0R2J-2-GP | 63.R0034.1DL | R402H16 | 4985.32 | 1305.48 | 270 | NO |
| R668 | R402H16 | 0R2J-2-GP | 63.R0034.1DL | R402H16 | 5656.9 | 1317.3 | 180 | NO |
| R669 | R402H16 | 0R2J-2-GP | 63.R0034.1DL | R402H16 | 6137.09 | 1315.81 | 180 | NO |
| R670 | R402H16 | 0R2J-2-GP | 63.R0034.1DL | R402H16 | 7242.13 | 23.8 | 270 | NO |
| R671 | R402H16 | 0R2J-2-GP | 63.R0034.1DL | R402H16 | 7183.02 | 50.24 | 0 | NO |
| R672 | R402H16 | 0R2J-2-GP | 63.R0034.1DL | R402H16 | 1640 | 4595 | 180 | YES |
| R673 | R402H16 | 4K7R2F-GP | 64.47015.6DL | R402H16 | 10338.92 | 110.76 | 270 | NO |
| R674 | R402H16 | 100KR2F-L1-GP | 64.10035.6DL | R402H16 | 8773 | 290 | 0 | YES |
| R675 | R402H16 | 100KR2F-L1-GP | 64.10035.6DL | R402H16 | 8462.52 | 160 | 0 | NO |
| R676 | R402H16 | 100KR2F-L1-GP | 64.10035.6DL | R402H16 | 8422.52 | 160 | 0 | NO |
| R677 | R402H16 | 100KR2F-L1-GP | 64.10035.6DL | R402H16 | 8382.52 | 160 | 0 | NO |
| R678 | R402H16 | 100KR2F-L1-GP | 64.10035.6DL | R402H16 | 8342.52 | 160 | 0 | NO |
| R679 | R402H16 | 0R2J-2-GP | 63.R0034.1DL | R402H16 | 1408.46 | 4303.91 | 270 | YES |
| R680 | R402H16 | 100KR2F-L1-GP | 64.10035.6DL | R402H16 | 8302.52 | 160 | 0 | NO |
| R681 | R402H16 | 100KR2F-L1-GP | 64.10035.6DL | R402H16 | 8262.52 | 160 | 0 | NO |
| R682 | R402H16 | 100KR2F-L1-GP | 64.10035.6DL | R402H16 | 8222.52 | 160 | 0 | NO |
| R683 | R402H16 | 0R2J-2-GP | 63.R0034.1DL | R402H16 | 7581 | 351 | 90 | NO |
| R684 | R402H16 | 0R2J-2-GP | 63.R0034.1DL | R402H16 | 967 | 4714 | 0 | NO |
| R685 | R402H16 | 0R2J-2-GP | 63.R0034.1DL | R402H16 | 686.4 | 5272.7 | 270 | NO |
| R686 | R402H16 | 0R2J-2-GP | 63.R0034.1DL | R402H16 | 2100.86 | 2031 | 0 | YES |
| R687 | R402H16 | 0R2J-2-GP | 63.R0034.1DL | R402H16 | 323 | 5335 | 90 | NO |
| R688 | R402H16 | 10KR2J-3-GP | 63.10334.1DL | R402H16 | 268 | 7204 | 90 | NO |
| R689 | R402H16 | 4K7R2F-GP | 64.47015.6DL | R402H16 | 13781.34 | 1752.09 | 0 | NO |
| R690 | R603H22 | 10KR3F-L-GP | 64.10025.55L | R603H22 | 884.5 | 7021.5 | 270 | NO |
| R691 | R402H16 | 0R2J-2-GP | 63.R0034.1DL | R402H16 | 809.5 | 7036.5 | 180 | NO |
| R692 | R603H22 | 1K33R3F-GP | 64.13315.55L | R603H22 | 764.5 | 7021.5 | 0 | NO |
| R693 | R402H16 | 4K7R2F-GP | 64.47015.6DL | R402H16 | 10188.459999999999 | 575.97 | 270 | YES |
| R694 | R402H16 | 4K7R2F-GP | 64.47015.6DL | R402H16 | 13591.24 | 1731.2 | 0 | NO |
| R695 | R402H16 | 4K7R2F-GP | 64.47015.6DL | R402H16 | 1274 | 4066 | 180 | NO |
| R696 | R402H16 | 4K7R2F-GP | 64.47015.6DL | R402H16 | 7596 | 865 | 270 | NO |
| R697 | R402H16 | 4K7R2F-GP | 64.47015.6DL | R402H16 | 10353.209999999999 | 269.20999999999998 | 90 | NO |
| R698 | R1206H26 | 56R6J-GP | 63.56032.11L | R1206H26 | 2164.69 | 1740.25 | 0 | NO |
| R699 | R402H16 | 4K7R2F-GP | 64.47015.6DL | R402H16 | 7596 | 823 | 270 | NO |
| R700 | R402H16 | 4K7R2F-GP | 64.47015.6DL | R402H16 | 2499.9499999999998 | 1004.58 | 0 | YES |
| R701 | R402H16 | 4K7R2F-GP | 64.47015.6DL | R402H16 | 2326 | 1003 | 0 | YES |
| R702 | R402H16 | 4K7R2F-GP | 64.47015.6DL | R402H16 | 7966 | 742 | 270 | NO |
| R703 | R402H16 | 4K7R2F-GP | 64.47015.6DL | R402H16 | 7766 | 740 | 270 | NO |
| R704 | R402H16 | 0R2J-2-GP | 63.R0034.1DL | R402H16 | 950 | 4846 | 270 | YES |
| R705 | R402H16 | 0R2J-2-GP | 63.R0034.1DL | R402H16 | 1130 | 4605 | 0 | YES |
| R706 | R402H16 | 4K7R2F-GP | 64.47015.6DL | R402H16 | 7859 | 741 | 90 | NO |
| R707 | R402H16 | 0R2J-2-GP | 63.R0034.1DL | R402H16 | 2256.62 | 4953 | 90 | NO |
| R708 | R402H16 | 0R2J-2-GP | 63.R0034.1DL | R402H16 | 2256.5 | 4912 | 90 | NO |
| R709 | R402H16 | 10KR2F-2-GP | 64.10025.6DL | R402H16 | 1139.3399999999999 | 4411.5 | 270 | NO |
| R710 | R402H16 | 1KR2F-3-GP | 64.10015.6DL | R402H16 | 8710 | 805 | 180 | YES |
| R711 | R402H16 | 0R2J-2-GP | 63.R0034.1DL | R402H16 | 823.42 | 4635.49 | 270 | YES |
| R712 | R402H16 | 1MR2F-GP | 64.10045.6DL | R402H16 | 6151 | 3635 | 180 | NO |
| R713 | R402H16 | 4K7R2F-GP | 64.47015.6DL | R402H16 | 8931 | 364 | 180 | YES |
| R714 | R402H16 | 4K7R2F-GP | 64.47015.6DL | R402H16 | 8640 | 528 | 270 | NO |
| R715 | R402H16 | 4K7R2F-GP | 64.47015.6DL | R402H16 | 10330 | 680 | 180 | NO |
| R716 | R402H16 | 0R2J-2-GP | 63.R0034.1DL | R402H16 | 7190.05 | 149.63999999999999 | 270 | NO |
| R717 | R402H16 | 0R2J-2-GP | 63.R0034.1DL | R402H16 | 7133.75 | 262.02 | 0 | NO |
| R718 | R402H16 | 0R2J-2-GP | 63.R0034.1DL | R402H16 | 12700.05 | 1319.21 | 180 | NO |
| R719 | R402H16 | 0R2J-2-GP | 63.R0034.1DL | R402H16 | 10613.42 | 666.94 | 0 | YES |
| R720 | R402H16 | 0R2J-2-GP | 63.R0034.1DL | R402H16 | 11734.79 | 1318.71 | 180 | NO |
| R721 | R402H16 | 0R2J-2-GP | 63.R0034.1DL | R402H16 | 12167.52 | 1318.15 | 180 | NO |
| R722 | R402H16 | 0R2J-2-GP | 63.R0034.1DL | R402H16 | 10654.75 | 505.73 | 180 | YES |
| R723 | R402H16 | 0R2J-2-GP | 63.R0034.1DL | R402H16 | 10654.75 | 425.73 | 0 | YES |
| R724 | R402H16 | 0R2J-2-GP | 63.R0034.1DL | R402H16 | 10452 | 366.15 | 270 | YES |
| R725 | R402H16 | 0R2J-2-GP | 63.R0034.1DL | R402H16 | 10532 | 366.15 | 90 | YES |
| R726 | R402H16 | 0R2J-2-GP | 63.R0034.1DL | R402H16 | 12659.97 | 1319.22 | 180 | NO |
| R727 | R402H16 | 0R2J-2-GP | 63.R0034.1DL | R402H16 | 11694.67 | 1318.76 | 180 | NO |
| R728 | R402H16 | 0R2J-2-GP | 63.R0034.1DL | R402H16 | 10613.42 | 740.96 | 180 | YES |
| R729 | R402H16 | 0R2J-2-GP | 63.R0034.1DL | R402H16 | 12127.48 | 1318.15 | 180 | NO |
| R730 | R402H16 | 15KR2F-GP | 64.15025.6DL | R402H16 | 5366.25 | 1634.63 | 90 | NO |
| R731 | R402H16 | 0R2J-2-GP | 63.R0034.1DL | R402H16 | 1202.52 | 4420.5200000000004 | 180 | NO |
| R732 | R402H16 | 0R2J-2-GP | 63.R0034.1DL | R402H16 | 3166.46 | 2952.75 | 0 | NO |
| R733 | R402H16 | 0R2J-2-GP | 63.R0034.1DL | R402H16 | 2589 | 2953 | 0 | NO |
| R734 | R1206H26 | 47R6F-GP | 64.47R05.41L | R1206H26 | 1291.8900000000001 | 3299.36 | 180 | NO |
| R735 | R402H16 | 10KR2F-2-GP | 64.10025.6DL | R402H16 | 1438.13 | 3223.5 | 270 | NO |
| R736 | R402H16 | 0R2J-2-GP | 63.R0034.1DL | R402H16 | 2259 | 1036 | 180 | NO |
| R737 | R402H16 | 0R2J-2-GP | 63.R0034.1DL | R402H16 | 2612 | 1036 | 0 | NO |
| R738 | R603H22 | 10KR3F-L-GP | 64.10025.55L | R603H22 | 377 | 6905 | 0 | NO |
| R739 | R402H16 | 0R2J-2-GP | 63.R0034.1DL | R402H16 | 2522.2800000000002 | 1248.04 | 270 | NO |
| R740 | R402H16 | 0R2J-2-GP | 63.R0034.1DL | R402H16 | 3027 | 2962.62 | 0 | NO |
| R741 | R402H16 | 4K7R2F-GP | 64.47015.6DL | R402H16 | 10159.48 | 1035 | 180 | NO |
| R742 | R402H16 | 4K7R2F-GP | 64.47015.6DL | R402H16 | 10200 | 1035 | 180 | NO |
| R743 | R402H16 | 0R2J-2-GP | 63.R0034.1DL | R402H16 | 824.62 | 5586.4 | 90 | YES |
| R744 | R402H16 | 4K7R2F-GP | 64.47015.6DL | R402H16 | 10325 | 1035 | 180 | NO |
| R745 | R402H16 | 4K7R2F-GP | 64.47015.6DL | R402H16 | 10280 | 1035 | 180 | NO |
| R746 | R402H16 | 4K7R2F-GP | 64.47015.6DL | R402H16 | 4744 | 672 | 0 | NO |
| R747 | R402H16 | 4K7R2F-GP | 64.47015.6DL | R402H16 | 10240 | 1035 | 180 | NO |
| R748 | R402H16 | 4K7R2F-GP | 64.47015.6DL | R402H16 | 4660 | 672 | 0 | NO |
| R749 | R402H16 | 0R2J-2-GP | 63.R0034.1DL | R402H16 | 8371 | 1056 | 270 | NO |
| R750 | R402H16 | 4K7R2F-GP | 64.47015.6DL | R402H16 | 4577 | 672 | 0 | NO |
| R751 | R402H16 | 4K7R2F-GP | 64.47015.6DL | R402H16 | 4784 | 672 | 180 | NO |
| R752 | R402H16 | 4K7R2F-GP | 64.47015.6DL | R402H16 | 4702 | 672 | 180 | NO |
| R753 | R402H16 | 4K7R2F-GP | 64.47015.6DL | R402H16 | 4619 | 672 | 180 | NO |
| R754 | R402H16 | 33D2R2F-GP | 64.33R25.6DL | R402H16 | 5424.9 | 1621.01 | 180 | NO |
| R755 | R402H16 | 150R2F-1-GP | 64.15005.6DL | R402H16 | 5701 | 2040 | 0 | NO |
| R756 | R402H16 | 0R2J-2-GP | 63.R0034.1DL | R402H16 | 5283 | 1618.15 | 270 | NO |
| R757 | R402H16 | 0R2J-2-GP | 63.R0034.1DL | R402H16 | 5631 | 1630 | 180 | NO |
| R758 | R402H16 | 0R2J-2-GP | 63.R0034.1DL | R402H16 | 5367.12 | 1590.35 | 90 | NO |
| R759 | R402H16 | 0R2J-2-GP | 63.R0034.1DL | R402H16 | 5283 | 1577.15 | 270 | NO |
| R760 | R402H16 | 3K3R2F-2-GP | 64.33015.6DL | R402H16 | 9990 | 1028 | 180 | YES |
| R761 | R402H16 | 0R2J-2-GP | 63.R0034.1DL | R402H16 | 5545 | 1633 | 180 | NO |
| R762 | R402H16 | 0R2J-2-GP | 63.R0034.1DL | R402H16 | 5073 | 1807 | 180 | NO |
| R763 | R402H16 | 4K7R2F-GP | 64.47015.6DL | R402H16 | 7672 | 1335 | 270 | NO |
| R764 | R402H16 | 1KR2F-3-GP | 64.10015.6DL | R402H16 | 10460 | 1035 | 180 | NO |
| R765 | R402H16 | 4K7R2F-GP | 64.47015.6DL | R402H16 | 7811 | 1369 | 180 | NO |
| R766 | R402H16 | 1KR2F-3-GP | 64.10015.6DL | R402H16 | 10505 | 1035 | 180 | NO |
| R767 | R402H16 | 4K7R2F-GP | 64.47015.6DL | R402H16 | 5756 | 1629 | 180 | NO |
| R768 | R402H16 | 4K7R2F-GP | 64.47015.6DL | R402H16 | 5714 | 1630 | 180 | NO |
| R769 | R402H16 | 4K7R2F-GP | 64.47015.6DL | R402H16 | 5672 | 1630 | 180 | NO |
| R770 | R402H16 | 4K7R2F-GP | 64.47015.6DL | R402H16 | 5504 | 1633 | 180 | NO |
| R771 | R402H16 | 4K7R2F-GP | 64.47015.6DL | R402H16 | 5283 | 1658.15 | 270 | NO |
| R772 | R402H16 | 3K3R2F-2-GP | 64.33015.6DL | R402H16 | 10031 | 1028 | 180 | YES |
| R773 | R402H16 | 1KR2F-3-GP | 64.10015.6DL | R402H16 | 5068 | 1865 | 90 | NO |
| R774 | R402H16 | 4K7R2F-GP | 64.47015.6DL | R402H16 | 7672 | 1253 | 90 | NO |
| R775 | R402H16 | 3K3R2F-2-GP | 64.33015.6DL | R402H16 | 9865.52 | 1028 | 180 | YES |
| R776 | R402H16 | 3K3R2F-2-GP | 64.33015.6DL | R402H16 | 9905.52 | 1028 | 180 | YES |
| R777 | R402H16 | 2KR2F-3-GP | 64.20015.6DL | R402H16 | 10415 | 1035 | 180 | NO |
| R778 | R402H16 | 4K7R2F-GP | 64.47015.6DL | R402H16 | 7672 | 1294 | 90 | NO |
| R779 | R402H16 | 2KR2F-3-GP | 64.20015.6DL | R402H16 | 10370 | 1035 | 180 | NO |
| R780 | R402H16 | 4K7R2F-GP | 64.47015.6DL | R402H16 | 9560 | 915 | 180 | YES |
| R781 | R402H16 | 4K7R2F-GP | 64.47015.6DL | R402H16 | 9425 | 915 | 180 | NO |
| R782 | R402H16 | 4K7R2F-GP | 64.47015.6DL | R402H16 | 9380 | 915 | 180 | YES |
| R783 | R402H16 | 4K7R2F-GP | 64.47015.6DL | R402H16 | 9470 | 915 | 180 | NO |
| R784 | R402H16 | 4K7R2F-GP | 64.47015.6DL | R402H16 | 9245 | 915 | 180 | YES |
| R785 | R402H16 | 4K7R2F-GP | 64.47015.6DL | R402H16 | 9515 | 915 | 180 | NO |
| R786 | R402H16 | 4K7R2F-GP | 64.47015.6DL | R402H16 | 9290 | 915 | 180 | YES |
| R787 | R402H16 | 4K7R2F-GP | 64.47015.6DL | R402H16 | 9335 | 915 | 180 | YES |
| R788 | R402H16 | 4K7R2F-GP | 64.47015.6DL | R402H16 | 9200 | 915 | 180 | YES |
| R789 | R402H16 | 4K7R2F-GP | 64.47015.6DL | R402H16 | 9155 | 915 | 180 | YES |
| R790 | R402H16 | 4K7R2F-GP | 64.47015.6DL | R402H16 | 9110 | 915 | 180 | YES |
| R791 | R402H16 | 4K7R2F-GP | 64.47015.6DL | R402H16 | 7753 | 1352 | 90 | NO |
| R792 | R402H16 | 4K7R2F-GP | 64.47015.6DL | R402H16 | 9560 | 805 | 0 | YES |
| R793 | R402H16 | 4K7R2F-GP | 64.47015.6DL | R402H16 | 9560 | 915 | 0 | NO |
| R794 | R402H16 | 4K7R2F-GP | 64.47015.6DL | R402H16 | 9425 | 915 | 0 | YES |
| R795 | R402H16 | 4K7R2F-GP | 64.47015.6DL | R402H16 | 9425 | 805 | 0 | YES |
| R796 | R402H16 | 4K7R2F-GP | 64.47015.6DL | R402H16 | 9380 | 915 | 0 | NO |
| R797 | R402H16 | 4K7R2F-GP | 64.47015.6DL | R402H16 | 9380 | 805 | 0 | YES |
| R798 | R402H16 | 4K7R2F-GP | 64.47015.6DL | R402H16 | 9470 | 915 | 0 | YES |
| R799 | R402H16 | 4K7R2F-GP | 64.47015.6DL | R402H16 | 2117.5 | 4917.4399999999996 | 270 | YES |
| R800 | R402H16 | 4K7R2F-GP | 64.47015.6DL | R402H16 | 7672 | 1212 | 270 | NO |
| R801 | R402H16 | 4K7R2F-GP | 64.47015.6DL | R402H16 | 2115 | 4820 | 270 | NO |
| R802 | R402H16 | 4K7R2F-GP | 64.47015.6DL | R402H16 | 2115 | 4860 | 270 | NO |
| R803 | R402H16 | 4K7R2F-GP | 64.47015.6DL | R402H16 | 2116 | 4944 | 270 | NO |
| R804 | R402H16 | 4K7R2F-GP | 64.47015.6DL | R402H16 | 2115 | 4900 | 270 | NO |
| R805 | R402H16 | 4K7R2F-GP | 64.47015.6DL | R402H16 | 4788 | 1210 | 0 | NO |
| R806 | R402H16 | 0R2J-2-GP | 63.R0034.1DL | R402H16 | 1927.33 | 4598.32 | 0 | NO |
| R807 | R402H16 | 4K7R2F-GP | 64.47015.6DL | R402H16 | 9470 | 805 | 0 | YES |
| R808 | R402H16 | 4K7R2F-GP | 64.47015.6DL | R402H16 | 9245 | 915 | 0 | NO |
| R809 | R402H16 | 4K7R2F-GP | 64.47015.6DL | R402H16 | 9245 | 805 | 0 | YES |
| R810 | R402H16 | 4K7R2F-GP | 64.47015.6DL | R402H16 | 9515 | 915 | 0 | YES |
| R811 | R402H16 | 4K7R2F-GP | 64.47015.6DL | R402H16 | 9515 | 805 | 0 | YES |
| R812 | R402H16 | 4K7R2F-GP | 64.47015.6DL | R402H16 | 9290 | 915 | 0 | NO |
| R813 | R402H16 | 4K7R2F-GP | 64.47015.6DL | R402H16 | 9290 | 805 | 0 | YES |
| R814 | R402H16 | 4K7R2F-GP | 64.47015.6DL | R402H16 | 9335 | 915 | 0 | NO |
| R815 | R402H16 | 4K7R2F-GP | 64.47015.6DL | R402H16 | 9335 | 805 | 0 | YES |
| R816 | R402H16 | 4K7R2F-GP | 64.47015.6DL | R402H16 | 9200 | 915 | 0 | NO |
| R817 | R402H16 | 4K7R2F-GP | 64.47015.6DL | R402H16 | 9200 | 805 | 0 | YES |
| R818 | R402H16 | 4K7R2F-GP | 64.47015.6DL | R402H16 | 9155 | 915 | 0 | NO |
| R819 | R402H16 | 4K7R2F-GP | 64.47015.6DL | R402H16 | 9155 | 805 | 0 | YES |
| R820 | R402H16 | 4K7R2F-GP | 64.47015.6DL | R402H16 | 9110 | 915 | 0 | NO |
| R821 | R402H16 | 4K7R2F-GP | 64.47015.6DL | R402H16 | 9110 | 805 | 0 | YES |
| R822 | R402H16 | 4K7R2F-GP | 64.47015.6DL | R402H16 | 9554 | 707 | 180 | NO |
| R823 | R402H16 | 4K7R2F-GP | 64.47015.6DL | R402H16 | 8104.13 | 1188.98 | 270 | NO |
| R824 | R402H16 | 4K7R2F-GP | 64.47015.6DL | R402H16 | 7596 | 1029 | 270 | NO |
| R825 | R402H16 | 0R2J-2-GP | 63.R0034.1DL | R402H16 | 9065 | 915 | 180 | YES |
| R826 | R402H16 | 0R2J-2-GP | 63.R0034.1DL | R402H16 | 9020 | 915 | 180 | YES |
| R827 | R402H16 | 0R2J-2-GP | 63.R0034.1DL | R402H16 | 8975 | 915 | 180 | YES |
| R828 | R402H16 | 0R2J-2-GP | 63.R0034.1DL | R402H16 | 8930 | 915 | 180 | YES |
| R829 | R402H16 | 0R2J-2-GP | 63.R0034.1DL | R402H16 | 8885 | 915 | 180 | YES |
| R830 | R402H16 | 0R2J-2-GP | 63.R0034.1DL | R402H16 | 8840 | 915 | 180 | YES |
| R831 | R402H16 | 0R2J-2-GP | 63.R0034.1DL | R402H16 | 8795 | 915 | 180 | YES |
| R832 | R402H16 | 0R2J-2-GP | 63.R0034.1DL | R402H16 | 8750 | 915 | 180 | YES |
| R833 | R402H16 | 4K7R2F-GP | 64.47015.6DL | R402H16 | 7653 | 1059 | 180 | NO |
| R834 | R402H16 | 4K7R2F-GP | 64.47015.6DL | R402H16 | 7596 | 947 | 90 | NO |
| R835 | R402H16 | 4K7R2F-GP | 64.47015.6DL | R402H16 | 8085 | 906 | 270 | NO |
| R836 | R402H16 | 4K7R2F-GP | 64.47015.6DL | R402H16 | 7596 | 988 | 90 | NO |
| R837 | R402H16 | 4K7R2F-GP | 64.47015.6DL | R402H16 | 7694 | 1059 | 0 | NO |
| R838 | R402H16 | 4K7R2F-GP | 64.47015.6DL | R402H16 | 7596 | 906 | 270 | NO |
| R839 | R402H16 | 4K7R2F-GP | 64.47015.6DL | R402H16 | 8295.6 | 1056.3 | 90 | NO |
| R861 | R402H16 | 0R2J-2-GP | 63.R0034.1DL | R402H16 | 4807 | 3613 | 180 | NO |
| R862 | R402H16 | 0R2J-2-GP | 63.R0034.1DL | R402H16 | 4807 | 3993 | 0 | NO |
| R863 | R402H16 | 0R2J-2-GP | 63.R0034.1DL | R402H16 | 4762 | 3613 | 0 | NO |
| R864 | R402H16 | 0R2J-2-GP | 63.R0034.1DL | R402H16 | 4762 | 3993 | 180 | NO |
| R865 | R402H16 | 0R2J-2-GP | 63.R0034.1DL | R402H16 | 1672 | 7214 | 0 | NO |
| R866 | R402H16 | 0R2J-2-GP | 63.R0034.1DL | R402H16 | 1672 | 7594 | 180 | NO |
| R867 | R402H16 | 0R2J-2-GP | 63.R0034.1DL | R402H16 | 1717 | 7214 | 180 | NO |
| R868 | R402H16 | 0R2J-2-GP | 63.R0034.1DL | R402H16 | 1717 | 7594 | 0 | NO |
| R869 | R402H16 | 0R2J-2-GP | 63.R0034.1DL | R402H16 | 1673 | 7378 | 180 | YES |
| R870 | R402H16 | 0R2J-2-GP | 63.R0034.1DL | R402H16 | 1713 | 7378 | 180 | YES |
| R871 | R402H16 | 2KR2F-3-GP | 64.20015.6DL | R402H16 | 1657 | 7534 | 90 | NO |
| R872 | R402H16 | 10KR2F-2-GP | 64.10025.6DL | R402H16 | 1847 | 7344 | 180 | NO |
| R873 | R402H16 | 2KR2F-3-GP | 64.20015.6DL | R402H16 | 1732 | 7534 | 270 | NO |
| R874 | R402H16 | 10KR2F-2-GP | 64.10025.6DL | R402H16 | 1537 | 7424 | 180 | NO |
| R875 | R402H16 | 10KR2F-2-GP | 64.10025.6DL | R402H16 | 1775 | 7895 | 180 | NO |
| R876 | R402H16 | 4K7R2J-2-GP | 63.47234.1DL | R402H16 | 1585 | 8085 | 90 | NO |
| R877 | R402H16 | 10KR2F-2-GP | 64.10025.6DL | R402H16 | 1465 | 7975 | 180 | NO |
| R878 | R402H16 | 4K7R2J-2-GP | 63.47234.1DL | R402H16 | 1660 | 8085 | 270 | NO |
| R879 | R402H16 | 0R2J-2-GP | 63.R0034.1DL | R402H16 | 1600 | 7765 | 0 | NO |
| R880 | R402H16 | 0R2J-2-GP | 63.R0034.1DL | R402H16 | 1600 | 8145 | 180 | NO |
| R881 | R402H16 | 0R2J-2-GP | 63.R0034.1DL | R402H16 | 1600 | 7935 | 180 | YES |
| R882 | R402H16 | 0R2J-2-GP | 63.R0034.1DL | R402H16 | 1640 | 7935 | 180 | YES |
| R883 | R402H16 | 0R2J-2-GP | 63.R0034.1DL | R402H16 | 1645 | 8145 | 0 | NO |
| R884 | R402H16 | 0R2J-2-GP | 63.R0034.1DL | R402H16 | 1645 | 7765 | 180 | NO |
| R885 | R402H16 | 10KR2F-2-GP | 64.10025.6DL | R402H16 | 2170 | 7660 | 180 | NO |
| R886 | R402H16 | 4K7R2J-2-GP | 63.47234.1DL | R402H16 | 1980 | 7850 | 90 | NO |
| R887 | R402H16 | 10KR2F-2-GP | 64.10025.6DL | R402H16 | 1860 | 7740 | 180 | NO |
| R888 | R402H16 | 4K7R2J-2-GP | 63.47234.1DL | R402H16 | 2055 | 7850 | 270 | NO |
| R889 | R402H16 | 0R2J-2-GP | 63.R0034.1DL | R402H16 | 1995 | 7530 | 0 | NO |
| R890 | R402H16 | 0R2J-2-GP | 63.R0034.1DL | R402H16 | 1995 | 7910 | 180 | NO |
| R891 | R402H16 | 0R2J-2-GP | 63.R0034.1DL | R402H16 | 2035 | 7700 | 180 | YES |
| R892 | R402H16 | 0R2J-2-GP | 63.R0034.1DL | R402H16 | 1995 | 7700 | 180 | YES |
| R893 | R402H16 | 0R2J-2-GP | 63.R0034.1DL | R402H16 | 2040 | 7530 | 180 | NO |
| R894 | R402H16 | 0R2J-2-GP | 63.R0034.1DL | R402H16 | 2040 | 7910 | 0 | NO |
| R895 | R402H16 | 10KR2F-2-GP | 64.10025.6DL | R402H16 | 2170 | 7105 | 180 | NO |
| R896 | R402H16 | 10KR2F-2-GP | 64.10025.6DL | R402H16 | 1860 | 7185 | 180 | NO |
| R897 | R402H16 | 4K7R2J-2-GP | 63.47234.1DL | R402H16 | 1980 | 7295 | 90 | NO |
| R898 | R402H16 | 4K7R2J-2-GP | 63.47234.1DL | R402H16 | 2055 | 7295 | 270 | NO |
| R899 | R402H16 | 0R2J-2-GP | 63.R0034.1DL | R402H16 | 1995 | 6975 | 0 | NO |
| R900 | R402H16 | 0R2J-2-GP | 63.R0034.1DL | R402H16 | 1995 | 7355 | 180 | NO |
| R901 | R402H16 | 0R2J-2-GP | 63.R0034.1DL | R402H16 | 2035 | 7145 | 180 | YES |
| R902 | R402H16 | 0R2J-2-GP | 63.R0034.1DL | R402H16 | 1995 | 7145 | 180 | YES |
| R903 | R402H16 | 0R2J-2-GP | 63.R0034.1DL | R402H16 | 2040 | 7355 | 0 | NO |
| R904 | R402H16 | 0R2J-2-GP | 63.R0034.1DL | R402H16 | 2040 | 6975 | 180 | NO |
| R931 | R402H16 | 4K7R2F-GP | 64.47015.6DL | R402H16 | 4984 | 2002 | 180 | NO |
| R932 | R402H16 | 4K7R2F-GP | 64.47015.6DL | R402H16 | 4926 | 1660 | 90 | NO |
| R933 | R402H16 | 4K7R2F-GP | 64.47015.6DL | R402H16 | 4774.66 | 1845.2 | 0 | NO |
| R934 | R402H16 | 4K7R2F-GP | 64.47015.6DL | R402H16 | 4618.49 | 2109.89 | 270 | NO |
| R941 | R402H16 | 0R2J-2-GP | 63.R0034.1DL | R402H16 | 2022.6 | 2893.06 | 270 | NO |
| R942 | R402H16 | 0R2J-2-GP | 63.R0034.1DL | R402H16 | 1923.15 | 2895.01 | 270 | NO |
| R943 | R402H16 | 4K7R2F-GP | 64.47015.6DL | R402H16 | 7427 | 133 | 0 | NO |
| R944 | R402H16 | 100KR2F-L1-GP | 64.10035.6DL | R402H16 | 7659 | 262 | 90 | NO |
| R945 | R402H16 | 0R2J-2-GP | 63.R0034.1DL | R402H16 | 5174.09 | 2020.72 | 270 | NO |
| R946 | R402H16 | 0R2J-2-GP | 63.R0034.1DL | R402H16 | 5097.09 | 2021.72 | 270 | NO |
| R952 | R402H16 | 0R2J-2-GP | 63.R0034.1DL | R402H16 | 9065 | 290 | 90 | NO |
| R953 | R402H16 | 0R2J-2-GP | 63.R0034.1DL | R402H16 | 9065 | 330 | 90 | NO |
| R955 | R402H16 | 33R2J-2-GP | 63.33034.1DL | R402H16 | 5271.31 | 2351.8000000000002 | 180 | NO |
| R956 | R402H16 | 33R2J-2-GP | 63.33034.1DL | R402H16 | 5352.95 | 2352.58 | 180 | NO |
| R957 | R402H16 | 33R2J-2-GP | 63.33034.1DL | R402H16 | 5287.09 | 2931.83 | 0 | NO |
| R958 | R402H16 | 82R2F-4-GP | 064.82R05.06DS | R402H16 | 5369.53 | 2930.6 | 180 | NO |
| R959 | R402H16 | 33R2J-2-GP | 63.33034.1DL | R402H16 | 5476.99 | 2910.69 | 90 | NO |
| R960 | R402H16 | 4K7R2F-GP | 64.47015.6DL | R402H16 | 2811 | 2068 | 180 | NO |
| R961 | R402H16 | 300R2F-GP | 64.30005.6DL | R402H16 | 3130 | 2219 | 270 | NO |
| R962 | R402H16 | 4K7R2F-GP | 64.47015.6DL | R402H16 | 3107.82 | 2935.5 | 90 | NO |
| R963 | R402H16 | 4K7R2F-GP | 64.47015.6DL | R402H16 | 2630 | 2951 | 0 | NO |
| R964 | R402H16 | 0R2J-2-GP | 63.R0034.1DL | R402H16 | 1389 | 7278 | 90 | NO |
| R965 | R402H16 | 0R2J-2-GP | 63.R0034.1DL | R402H16 | 1009 | 7278 | 270 | NO |
| R966 | R402H16 | 0R2J-2-GP | 63.R0034.1DL | R402H16 | 1389 | 7323 | 270 | NO |
| R967 | R402H16 | 0R2J-2-GP | 63.R0034.1DL | R402H16 | 1009 | 7323 | 90 | NO |
| R968 | R402H16 | 4K7R2F-GP | 64.47015.6DL | R402H16 | 3206.62 | 2952.9 | 0 | NO |
| R1202 | R402H16 | 274R2F-GP | 64.27405.6DL | R402H16 | 690 | 5350 | 90 | YES |
| R1226 | R402H16 | 11KR2F-L-GP | 64.11025.6DL | R402H16 | 571 | 7130 | 90 | NO |
| R1227 | R402H16 | 100KR2F-L1-GP | 64.10035.6DL | R402H16 | 571 | 7089 | 270 | NO |
| R1848 | R603H22 | 10MR3F-GP | 64.10055.55L | R603H22 | 5209.09 | 3265.41 | 180 | NO |
| R2098 | R402H14 | 10R2F-L-GP | 64.10R05.6DL | R402H14 | 813 | 7409 | 270 | NO |
| R2099 | R402H16 | 39K2R2F-L-GP | 64.39225.6DL | R402H16 | 312 | 7109 | 180 | NO |
| R2102 | R402H16 | 26K1R2F-2-GP | 64.26125.6DL | R402H16 | 433 | 7114 | 0 | NO |
| R2103 | R402H16 | 150KR2J-GP | 63.15434.1DL | R402H16 | 390 | 7651 | 180 | NO |
| R2106 | R402H16 | 49K9R2F-L-GP | 64.49925.6DL | R402H16 | 813 | 7669 | 270 | NO |
| R2107 | R402H16 | 49K9R2F-L-GP | 64.49925.6DL | R402H16 | 813 | 7449 | 270 | NO |
| R2108 | R402H16 | 3K74R2F-GP | 64.37415.6DL | R402H16 | 813 | 7579 | 90 | NO |
| R2109 | R402H16 | 6K04R2F-GP | 64.60415.6DL | R402H16 | 813 | 7537 | 90 | NO |
| R2110 | R402H16 | 1KR2J-1-GP | 63.10234.1DL | R402H16 | 513 | 7114 | 0 | NO |
| R2111 | R402H14 | 10R2J-2-GP | 63.10034.1DL | R402H14 | 1260 | 7790 | 0 | NO |
| R2113 | R402H16 | 0R2J-2-GP | 63.R0034.1DL | R402H16 | 268 | 7469 | 270 | NO |
| R2114 | R402H16 | 0R2J-2-GP | 63.R0034.1DL | R402H16 | 1165 | 7560 | 90 | NO |
| R2115 | R402H16 | 0R2J-2-GP | 63.R0034.1DL | R402H16 | 1200 | 7750 | 270 | NO |
| R2117 | R402H15 | 100KR2J-4-GP | 63.10434.L1L | R402H15 | 567 | 7648 | 180 | NO |
| R2118 | R603H22 | 1MR3J-L-GP | 63.10533.15L | R603H22 | 1257 | 7563 | 90 | NO |
| R2119 | R402H14 | 10R2F-L-GP | 64.10R05.6DL | R402H14 | 784 | 7333 | 270 | YES |
| R2120 | R402H14 | 10R2F-L-GP | 64.10R05.6DL | R402H14 | 801 | 7313 | 270 | NO |
| R2122 | R402H14 | 10R2F-L-GP | 64.10R05.6DL | R402H14 | 784 | 7293 | 270 | YES |
| R2123 | R402H14 | 10R2F-L-GP | 64.10R05.6DL | R402H14 | 801 | 7273 | 270 | NO |
| R2171 | R402H15 | 100KR2J-4-GP | 63.10434.L1L | R402H15 | 650 | 7648 | 0 | NO |
| R2172 | R402H16 | 0R2J-2-GP | 63.R0034.1DL | R402H16 | 350 | 7651 | 180 | NO |
| R2174 | R402H15 | 100KR2J-4-GP | 63.10434.L1L | R402H15 | 608 | 7648 | 180 | NO |
| R2901 | R402H16 | 0R2J-2-GP | 63.R0034.1DL | R402H16 | 10781.24 | 350.54 | 270 | NO |
| R2902 | R402H16 | 0R2J-2-GP | 63.R0034.1DL | R402H16 | 10890.04 | 408.83 | 90 | NO |
| R2903 | R402H16 | 0R2J-2-GP | 63.R0034.1DL | R402H16 | 10775.69 | 269.5 | 270 | NO |
| R2904 | R402H16 | 0R2J-2-GP | 63.R0034.1DL | R402H16 | 10886.2 | 229.4 | 90 | NO |
| R2905 | R402H16 | 0R2J-2-GP | 63.R0034.1DL | R402H16 | 10890 | 50 | 90 | NO |
| R2906 | R402H16 | 0R2J-2-GP | 63.R0034.1DL | R402H16 | 10775.59 | 5 | 270 | NO |
| R2907 | R402H16 | 0R2J-2-GP | 63.R0034.1DL | R402H16 | 10697 | 63 | 0 | YES |
| R2908 | R402H16 | 0R2J-2-GP | 63.R0034.1DL | R402H16 | 10758 | 76 | 90 | YES |
| R2909 | R402H16 | 0R2J-2-GP | 63.R0034.1DL | R402H16 | 10890.04 | 363.83 | 90 | NO |
| R2910 | R402H16 | 0R2J-2-GP | 63.R0034.1DL | R402H16 | 10781.24 | 395.54 | 270 | NO |
| R2911 | R402H16 | 0R2J-2-GP | 63.R0034.1DL | R402H16 | 10775.69 | 224.5 | 270 | NO |
| R2912 | R402H16 | 0R2J-2-GP | 63.R0034.1DL | R402H16 | 10886.2 | 274.39999999999998 | 90 | NO |
| R2913 | R402H16 | 0R2J-2-GP | 63.R0034.1DL | R402H16 | 10758 | 35 | 90 | YES |
| R2914 | R402H16 | 0R2J-2-GP | 63.R0034.1DL | R402H16 | 10759 | 124 | 90 | YES |
| R2915 | R402H16 | 0R2J-2-GP | 63.R0034.1DL | R402H16 | 10890 | 5 | 90 | NO |
| R2916 | R402H16 | 0R2J-2-GP | 63.R0034.1DL | R402H16 | 10775.59 | 55 | 270 | NO |
| R2917 | R402H16 | 0R2J-2-GP | 63.R0034.1DL | R402H16 | 5178.2 | 1320.7 | 0 | YES |
| R2918 | R402H16 | 0R2J-2-GP | 63.R0034.1DL | R402H16 | 5258.2 | 1320.7 | 0 | YES |
| R2919 | R402H16 | 0R2J-2-GP | 63.R0034.1DL | R402H16 | 5743.45 | 1320.3 | 0 | YES |
| R2920 | R402H16 | 0R2J-2-GP | 63.R0034.1DL | R402H16 | 5824.67 | 1320.3 | 0 | YES |
| R2921 | R402H16 | 0R2J-2-GP | 63.R0034.1DL | R402H16 | 6460 | 1320 | 0 | YES |
| R2922 | R402H16 | 0R2J-2-GP | 63.R0034.1DL | R402H16 | 6550 | 1320 | 0 | YES |
| R2923 | R402H16 | 0R2J-2-GP | 63.R0034.1DL | R402H16 | 6160.26 | 1322.52 | 0 | YES |
| R2924 | R402H16 | 0R2J-2-GP | 63.R0034.1DL | R402H16 | 6240.48 | 1322.44 | 0 | YES |
| R2925 | R402H16 | 0R2J-2-GP | 63.R0034.1DL | R402H16 | 5138.2 | 1320.7 | 0 | YES |
| R2926 | R402H16 | 0R2J-2-GP | 63.R0034.1DL | R402H16 | 5218.2 | 1320.7 | 0 | YES |
| R2927 | R402H16 | 0R2J-2-GP | 63.R0034.1DL | R402H16 | 5703.45 | 1320.3 | 0 | YES |
| R2928 | R402H16 | 0R2J-2-GP | 63.R0034.1DL | R402H16 | 5784.67 | 1320.3 | 0 | YES |
| R2929 | R402H16 | 0R2J-2-GP | 63.R0034.1DL | R402H16 | 6505 | 1320 | 0 | YES |
| R2930 | R402H16 | 0R2J-2-GP | 63.R0034.1DL | R402H16 | 6595 | 1320 | 0 | YES |
| R2931 | R402H16 | 0R2J-2-GP | 63.R0034.1DL | R402H16 | 6120.26 | 1322.52 | 0 | YES |
| R2932 | R402H16 | 0R2J-2-GP | 63.R0034.1DL | R402H16 | 6200.48 | 1322.44 | 0 | YES |
| R2933 | R402H16 | 0R2J-2-GP | 63.R0034.1DL | R402H16 | 5042.4799999999996 | 1322.5 | 0 | NO |
| R2934 | R402H16 | 0R2J-2-GP | 63.R0034.1DL | R402H16 | 5002.38 | 1322.5 | 0 | NO |
| R2935 | R402H16 | 0R2J-2-GP | 63.R0034.1DL | R402H16 | 7289.6 | 168.3 | 0 | NO |
| R2936 | R402H16 | 0R2J-2-GP | 63.R0034.1DL | R402H16 | 7170.9 | 254.9 | 270 | YES |
| R2937 | R402H16 | 0R2J-2-GP | 63.R0034.1DL | R402H16 | 7168.3 | 491 | 270 | YES |
| R2938 | R402H16 | 0R2J-2-GP | 63.R0034.1DL | R402H16 | 779.91 | 3650.75 | 90 | NO |
| R2939 | R402H16 | 470KR2F-1-GP | 64.47035.L0L | R402H16 | 705.91 | 3648.99 | 0 | NO |
| R2940 | R402H16 | 100KR2F-L1-GP | 64.10035.6DL | R402H16 | 706.54 | 3725.6 | 0 | NO |
| R2941 | R402H16 | 10KR2F-2-GP | 64.10025.6DL | R402H16 | 778.05 | 3607.27 | 90 | NO |
| R2942 | R402H16 | 47KR2F-GP | 64.47025.6DL | R402H16 | 874 | 3600 | 90 | NO |
| R2943 | R402H16 | 10KR2F-2-GP | 64.10025.6DL | R402H16 | 1140 | 3886 | 270 | NO |
| R2944 | R402H16 | 4K75R2F-1-GP | 64.47515.6DL | R402H16 | 1177.6099999999999 | 3708.06 | 180 | NO |
| R2945 | R402H16 | 4K75R2F-1-GP | 64.47515.6DL | R402H16 | 800 | 4052 | 0 | NO |
| R2946 | R402H16 | 10KR2F-2-GP | 64.10025.6DL | R402H16 | 842.74 | 4008.41 | 0 | NO |
| R2947 | R402H16 | 10KR2F-2-GP | 64.10025.6DL | R402H16 | 826.9 | 3926.65 | 90 | NO |
| R2948 | R402H16 | 0R2J-2-GP | 63.R0034.1DL | R402H16 | 996 | 2720 | 90 | NO |
| R2949 | R402H16 | 0R2J-2-GP | 63.R0034.1DL | R402H16 | 1078 | 2301 | 90 | NO |
| R2950 | R402H16 | 4K75R2F-1-GP | 64.47515.6DL | R402H16 | 1045.07 | 3904.34 | 180 | NO |
| R2951 | R402H16 | 0R2J-2-GP | 63.R0034.1DL | R402H16 | 7207 | 166.7 | 0 | NO |
| R2952 | R402H16 | 0R2J-2-GP | 63.R0034.1DL | R402H16 | 7170.7 | 297 | 270 | YES |
| R2953 | R402H16 | 0R2J-2-GP | 63.R0034.1DL | R402H16 | 7168.3 | 532 | 270 | YES |
| R2954 | R402H16 | 0R2J-2-GP | 63.R0034.1DL | R402H16 | 7248.2 | 167.4 | 0 | NO |
| R2955 | R402H16 | 0R2J-2-GP | 63.R0034.1DL | R402H16 | 7226.59 | 286.13 | 270 | NO |
| R2960 | R402H16 | 0R2J-2-GP | 63.R0034.1DL | R402H16 | 4628.68 | 1206.24 | 180 | NO |
| R2961 | R402H16 | 0R2J-2-GP | 63.R0034.1DL | R402H16 | 4669.05 | 1206.28 | 180 | NO |
| R2962 | R402H16 | 0R2J-2-GP | 63.R0034.1DL | R402H16 | 10637.25 | 488.23 | 90 | YES |
| R2963 | R402H16 | 0R2J-2-GP | 63.R0034.1DL | R402H16 | 10637.25 | 443.23 | 90 | YES |
| R2964 | R402H16 | 0R2J-2-GP | 63.R0034.1DL | R402H16 | 10715 | 365 | 90 | YES |
| R2965 | R402H16 | 0R2J-2-GP | 63.R0034.1DL | R402H16 | 10670 | 245 | 90 | YES |
| R2966 | R402H16 | 0R2J-2-GP | 63.R0034.1DL | R402H16 | 10469.5 | 348.65 | 180 | YES |
| R2967 | R402H16 | 0R2J-2-GP | 63.R0034.1DL | R402H16 | 10514.5 | 348.65 | 180 | YES |
| R2968 | R402H16 | 0R2J-2-GP | 63.R0034.1DL | R402H16 | 8086 | 987 | 90 | NO |
| R2969 | R402H16 | 0R2J-2-GP | 63.R0034.1DL | R402H16 | 8086 | 946 | 90 | NO |
| R2974 | R402H16 | 0R2J-2-GP | 63.R0034.1DL | R402H16 | 10715 | 325 | 90 | YES |
| R2975 | R402H16 | 0R2J-2-GP | 63.R0034.1DL | R402H16 | 10670 | 205 | 90 | YES |
| R2976 | R402H16 | 0R2J-2-GP | 63.R0034.1DL | R402H16 | 10596.46 | 683.9 | 90 | YES |
| R2977 | R402H16 | 0R2J-2-GP | 63.R0034.1DL | R402H16 | 10596.46 | 724 | 90 | YES |
| R2978 | R402H16 | 10KR2F-2-GP | 64.10025.6DL | R402H16 | 723 | 5457 | 90 | YES |
| R2979 | R402H16 | 0R2J-2-GP | 63.R0034.1DL | R402H16 | 8134.25 | 1276.31 | 90 | NO |
| R2980 | R402H16 | 0R2J-2-GP | 63.R0034.1DL | R402H16 | 8134.25 | 1236.31 | 90 | NO |
| R3029 | R402H16 | 1KR2F-3-GP | 64.10015.6DL | R402H16 | 2575 | 5275 | 180 | NO |
| R3098 | R402H16 | 1KR2F-3-GP | 64.10015.6DL | R402H16 | 2250 | 5201 | 0 | NO |
| R3099 | R402H16 | 1KR2F-3-GP | 64.10015.6DL | R402H16 | 3174 | 5383 | 90 | NO |
| R3100 | R402H16 | 1KR2F-3-GP | 64.10015.6DL | R402H16 | 2210 | 5365 | 180 | YES |
| R3102 | R402H16 | 27R2F-GP | 64.27R05.6DL | R402H16 | 6360 | 3356 | 0 | NO |
| R3103 | R402H16 | 27R2F-GP | 64.27R05.6DL | R402H16 | 6400 | 3356 | 0 | NO |
| R3104 | R402H16 | 27R2F-GP | 64.27R05.6DL | R402H16 | 6540 | 3486 | 90 | NO |
| R3105 | R402H16 | 27R2F-GP | 64.27R05.6DL | R402H16 | 6540 | 3526 | 90 | NO |
| R3106 | R402H16 | 27R2F-GP | 64.27R05.6DL | R402H16 | 6540 | 3621 | 90 | NO |
| R3107 | R402H16 | 27R2F-GP | 64.27R05.6DL | R402H16 | 6540 | 3671 | 90 | NO |
| R3108 | R402H16 | 27R2F-GP | 64.27R05.6DL | R402H16 | 6405 | 3776 | 180 | NO |
| R3109 | R402H16 | 27R2F-GP | 64.27R05.6DL | R402H16 | 6363 | 3776 | 180 | NO |
| R3110 | R402H16 | 33R2F-3-GP | 64.33R05.6DL | R402H16 | 6067 | 3482 | 90 | NO |
| R3201 | R402H16 | 0R2J-2-GP | 63.R0034.1DL | R402H16 | 2936.78 | 7584.31 | 0 | YES |
| R3202 | R402H16 | 0R2J-2-GP | 63.R0034.1DL | R402H16 | 2896.78 | 7584.31 | 0 | YES |
| R3203 | R402H16 | 0R2J-2-GP | 63.R0034.1DL | R402H16 | 2956.78 | 7344.31 | 0 | YES |
| R3204 | R402H16 | 0R2J-2-GP | 63.R0034.1DL | R402H16 | 5066.78 | 8104.31 | 0 | YES |
| R3205 | R402H16 | 0R2J-2-GP | 63.R0034.1DL | R402H16 | 5026.78 | 8104.31 | 0 | YES |
| R3206 | R402H16 | 0R2J-2-GP | 63.R0034.1DL | R402H16 | 5087 | 7887 | 270 | YES |
| R3207 | R402H16 | 0R2J-2-GP | 63.R0034.1DL | R402H16 | 5241.78 | 8104.31 | 0 | YES |
| R3208 | R402H16 | 0R2J-2-GP | 63.R0034.1DL | R402H16 | 5201.78 | 8104.31 | 0 | YES |
| R3209 | R402H16 | 0R2J-2-GP | 63.R0034.1DL | R402H16 | 5246.78 | 7864.31 | 0 | YES |
| R3210 | R402H16 | 0R2J-2-GP | 63.R0034.1DL | R402H16 | 8645.6 | 7888.8 | 270 | YES |
| R3211 | R402H16 | 0R2J-2-GP | 63.R0034.1DL | R402H16 | 8569.4 | 7902.2 | 90 | YES |
| R3212 | R402H16 | 0R2J-2-GP | 63.R0034.1DL | R402H16 | 8684 | 7658 | 90 | YES |
| R3213 | R402H16 | 0R2J-2-GP | 63.R0034.1DL | R402H16 | 13109 | 7154 | 0 | YES |
| R3214 | R402H16 | 0R2J-2-GP | 63.R0034.1DL | R402H16 | 12980 | 7090 | 0 | YES |
| R3215 | R402H16 | 0R2J-2-GP | 63.R0034.1DL | R402H16 | 13129 | 6919 | 0 | YES |
| R3216 | R402H16 | 0R2J-2-GP | 63.R0034.1DL | R402H16 | 3111.78 | 7584.31 | 0 | YES |
| R3217 | R402H16 | 0R2J-2-GP | 63.R0034.1DL | R402H16 | 3071.78 | 7584.31 | 0 | YES |
| R3218 | R402H16 | 0R2J-2-GP | 63.R0034.1DL | R402H16 | 3116.78 | 7344.31 | 0 | YES |
| R3219 | R402H16 | 0R2J-2-GP | 63.R0034.1DL | R402H16 | 5386.78 | 8104.31 | 0 | YES |
| R3220 | R402H16 | 0R2J-2-GP | 63.R0034.1DL | R402H16 | 5346.78 | 8104.31 | 0 | YES |
| R3221 | R402H16 | 0R2J-2-GP | 63.R0034.1DL | R402H16 | 5406.78 | 7864.31 | 0 | YES |
| R3222 | R402H16 | 0R2J-2-GP | 63.R0034.1DL | R402H16 | 4925 | 8100 | 0 | YES |
| R3223 | R402H16 | 0R2J-2-GP | 63.R0034.1DL | R402H16 | 4820 | 8100 | 0 | YES |
| R3224 | R402H16 | 0R2J-2-GP | 63.R0034.1DL | R402H16 | 4919 | 7864 | 0 | YES |
| R3225 | R402H16 | 0R2J-2-GP | 63.R0034.1DL | R402H16 | 8802.1 | 7929.1 | 270 | YES |
| R3226 | R402H16 | 0R2J-2-GP | 63.R0034.1DL | R402H16 | 8786 | 7870 | 0 | YES |
| R3227 | R402H16 | 0R2J-2-GP | 63.R0034.1DL | R402H16 | 8822.0300000000007 | 7639.95 | 0 | YES |
| R3228 | R402H16 | 0R2J-2-GP | 63.R0034.1DL | R402H16 | 13299 | 7159 | 0 | YES |
| R3229 | R402H16 | 0R2J-2-GP | 63.R0034.1DL | R402H16 | 13259 | 7159 | 0 | YES |
| R3230 | R402H16 | 0R2J-2-GP | 63.R0034.1DL | R402H16 | 13304 | 6919 | 0 | YES |
| R3231 | R402H16 | 0R2J-2-GP | 63.R0034.1DL | R402H16 | 3256.78 | 7584.31 | 0 | YES |
| R3232 | R402H16 | 0R2J-2-GP | 63.R0034.1DL | R402H16 | 3216.78 | 7584.31 | 0 | YES |
| R3233 | R402H16 | 0R2J-2-GP | 63.R0034.1DL | R402H16 | 3276.78 | 7344.31 | 0 | YES |
| R3234 | R402H16 | 0R2J-2-GP | 63.R0034.1DL | R402H16 | 2795 | 7580 | 0 | YES |
| R3235 | R402H16 | 0R2J-2-GP | 63.R0034.1DL | R402H16 | 2630 | 7540 | 0 | YES |
| R3236 | R402H16 | 0R2J-2-GP | 63.R0034.1DL | R402H16 | 2780.5 | 7350.17 | 0 | YES |
| R3237 | R402H16 | 0R2J-2-GP | 63.R0034.1DL | R402H16 | 8961.7800000000007 | 7874.31 | 0 | YES |
| R3238 | R402H16 | 0R2J-2-GP | 63.R0034.1DL | R402H16 | 8921.7800000000007 | 7874.31 | 0 | YES |
| R3239 | R402H16 | 0R2J-2-GP | 63.R0034.1DL | R402H16 | 8983 | 7654 | 90 | YES |
| R3240 | R402H16 | 0R2J-2-GP | 63.R0034.1DL | R402H16 | 8448.1 | 7875.9 | 0 | YES |
| R3241 | R402H16 | 0R2J-2-GP | 63.R0034.1DL | R402H16 | 8370 | 7765 | 180 | YES |
| R3242 | R402H16 | 0R2J-2-GP | 63.R0034.1DL | R402H16 | 8524 | 7639 | 0 | YES |
| R3243 | R402H16 | 0R2J-2-GP | 63.R0034.1DL | R402H16 | 13449 | 7159 | 0 | YES |
| R3244 | R402H16 | 0R2J-2-GP | 63.R0034.1DL | R402H16 | 13409 | 7159 | 0 | YES |
| R3245 | R402H16 | 0R2J-2-GP | 63.R0034.1DL | R402H16 | 13469 | 6919 | 0 | YES |
| R3601 | R402H16 | 1KR2F-3-GP | 64.10015.6DL | R402H16 | 9907.11 | 141.6 | 270 | NO |
| R3602 | R402H16 | 1KR2F-3-GP | 64.10015.6DL | R402H16 | 9962.2999999999993 | 447.44 | 180 | NO |
| R3603 | R402H16 | 10KR2F-2-GP | 64.10025.6DL | R402H16 | 9864.17 | 185.87 | 90 | NO |
| R3604 | R402H16 | 0R2J-2-GP | 63.R0034.1DL | R402H16 | 849 | 5840 | 180 | NO |
| R3701 | R402H16 | 4K7R2F-GP | 64.47015.6DL | R402H16 | 9065 | 805 | 0 | YES |
| R3702 | R402H16 | 4K7R2F-GP | 64.47015.6DL | R402H16 | 9020 | 805 | 0 | YES |
| R3703 | R402H16 | 4K7R2F-GP | 64.47015.6DL | R402H16 | 8975 | 805 | 0 | YES |
| R3704 | R402H16 | 4K7R2F-GP | 64.47015.6DL | R402H16 | 8930 | 805 | 0 | YES |
| R3705 | R402H16 | 4K7R2F-GP | 64.47015.6DL | R402H16 | 8885 | 805 | 0 | YES |
| R3706 | R402H16 | 4K7R2F-GP | 64.47015.6DL | R402H16 | 8750 | 805 | 0 | YES |
| R3707 | R402H16 | 4K7R2F-GP | 64.47015.6DL | R402H16 | 8840 | 805 | 0 | YES |
| R3708 | R402H16 | 4K7R2F-GP | 64.47015.6DL | R402H16 | 8795 | 805 | 0 | YES |
| R3709 | R402H16 | 1KR2F-3-GP | 64.10015.6DL | R402H16 | 8342.52 | 160 | 0 | YES |
| R3710 | R402H16 | 1KR2F-3-GP | 64.10015.6DL | R402H16 | 8462.52 | 160 | 0 | YES |
| R3711 | R402H16 | 1KR2F-3-GP | 64.10015.6DL | R402H16 | 8202.1200000000008 | 159.19 | 0 | YES |
| R3712 | R402H16 | 1KR2F-3-GP | 64.10015.6DL | R402H16 | 8302.52 | 160 | 0 | YES |
| R3713 | R402H16 | 1KR2F-3-GP | 64.10015.6DL | R402H16 | 8261.3799999999992 | 153.04 | 0 | YES |
| R3714 | R402H16 | 1KR2F-3-GP | 64.10015.6DL | R402H16 | 8731 | 290 | 0 | YES |
| R3715 | R402H16 | 1KR2F-3-GP | 64.10015.6DL | R402H16 | 8422.52 | 160 | 0 | YES |
| R3716 | R402H16 | 1KR2F-3-GP | 64.10015.6DL | R402H16 | 8382.52 | 160 | 0 | YES |
| R3717 | R402H16 | 4K7R2F-GP | 64.47015.6DL | R402H16 | 9065 | 915 | 180 | NO |
| R3718 | R402H16 | 4K7R2F-GP | 64.47015.6DL | R402H16 | 9020 | 915 | 180 | NO |
| R3719 | R402H16 | 4K7R2F-GP | 64.47015.6DL | R402H16 | 8930 | 915 | 180 | NO |
| R3720 | R402H16 | 4K7R2F-GP | 64.47015.6DL | R402H16 | 8975 | 915 | 180 | NO |
| R3721 | R402H16 | 4K7R2F-GP | 64.47015.6DL | R402H16 | 8840 | 915 | 180 | NO |
| R3722 | R402H16 | 4K7R2F-GP | 64.47015.6DL | R402H16 | 8885 | 915 | 180 | NO |
| R3723 | R402H16 | 4K7R2F-GP | 64.47015.6DL | R402H16 | 8750 | 915 | 180 | NO |
| R3724 | R402H16 | 4K7R2F-GP | 64.47015.6DL | R402H16 | 8795 | 915 | 180 | NO |
| R3725 | R402H16 | 1KR2F-3-GP | 64.10015.6DL | R402H16 | 8478.81 | 54.99 | 270 | NO |
| R4102 | R402H16 | 4K7R2F-GP | 64.47015.6DL | R402H16 | 2824.06 | 7213.98 | 0 | YES |
| R4103 | R402H16 | 4K7R2F-GP | 64.47015.6DL | R402H16 | 2864.06 | 7213.98 | 0 | YES |
| R4104 | R402H16 | 4K7R2F-GP | 64.47015.6DL | R402H16 | 2945.06 | 7213.98 | 0 | YES |
| R4106 | R402H16 | 4K7R2F-GP | 64.47015.6DL | R402H16 | 3025.54 | 7214.13 | 0 | YES |
| R4107 | R402H16 | 4K7R2F-GP | 64.47015.6DL | R402H16 | 2985.54 | 7214.13 | 0 | YES |
| R4108 | R402H16 | 4K7R2F-GP | 64.47015.6DL | R402H16 | 3104.06 | 7213.98 | 0 | YES |
| R4110 | R402H16 | 4K7R2F-GP | 64.47015.6DL | R402H16 | 3194.06 | 7693.98 | 180 | YES |
| R4111 | R402H16 | 4K7R2F-GP | 64.47015.6DL | R402H16 | 3234.06 | 7693.98 | 180 | YES |
| R4112 | R402H16 | 4K7R2F-GP | 64.47015.6DL | R402H16 | 3034.06 | 7703.98 | 180 | YES |
| R4114 | R402H16 | 4K7R2F-GP | 64.47015.6DL | R402H16 | 2950.79 | 7703.5 | 180 | YES |
| R4115 | R402H16 | 4K7R2F-GP | 64.47015.6DL | R402H16 | 2991.64 | 7705.91 | 180 | YES |
| R4116 | R402H16 | 4K7R2F-GP | 64.47015.6DL | R402H16 | 2869.06 | 7703.98 | 180 | YES |
| R4118 | R402H16 | 4K7R2F-GP | 64.47015.6DL | R402H16 | 5289.06 | 8223.98 | 180 | YES |
| R4119 | R402H16 | 4K7R2F-GP | 64.47015.6DL | R402H16 | 5249.06 | 8223.98 | 180 | YES |
| R4120 | R402H16 | 4K7R2F-GP | 64.47015.6DL | R402H16 | 4999.0600000000004 | 7733.98 | 0 | YES |
| R4122 | R402H16 | 4K7R2F-GP | 64.47015.6DL | R402H16 | 5169.0600000000004 | 8223.98 | 180 | YES |
| R4123 | R402H16 | 4K7R2F-GP | 64.47015.6DL | R402H16 | 5137 | 7732 | 0 | YES |
| R4125 | R402H16 | 4K7R2F-GP | 64.47015.6DL | R402H16 | 5178 | 7732 | 0 | YES |
| R4126 | R402H16 | 4K7R2F-GP | 64.47015.6DL | R402H16 | 5219 | 7731 | 0 | YES |
| R4127 | R402H16 | 4K7R2F-GP | 64.47015.6DL | R402H16 | 5085.79 | 8223.5 | 180 | YES |
| R4128 | R402H16 | 4K7R2F-GP | 64.47015.6DL | R402H16 | 5126.79 | 8223.5 | 180 | YES |
| R4129 | R402H16 | 4K7R2F-GP | 64.47015.6DL | R402H16 | 4959.0600000000004 | 7733.98 | 0 | YES |
| R4130 | R402H16 | 4K7R2F-GP | 64.47015.6DL | R402H16 | 5270 | 7732 | 0 | YES |
| R4133 | R402H16 | 4K7R2F-GP | 64.47015.6DL | R402H16 | 5004.0600000000004 | 8223.98 | 180 | YES |
| R4134 | R402H16 | 4K7R2F-GP | 64.47015.6DL | R402H16 | 8984.06 | 7993.98 | 180 | YES |
| R4135 | R402H16 | 4K7R2F-GP | 64.47015.6DL | R402H16 | 8689.06 | 7503.98 | 0 | YES |
| R4136 | R402H16 | 4K7R2F-GP | 64.47015.6DL | R402H16 | 8944.06 | 7993.98 | 180 | YES |
| R4138 | R402H16 | 4K7R2F-GP | 64.47015.6DL | R402H16 | 8862.76 | 8020.08 | 180 | YES |
| R4139 | R402H16 | 4K7R2F-GP | 64.47015.6DL | R402H16 | 8813.06 | 7503.98 | 0 | YES |
| R4141 | R402H16 | 4K7R2F-GP | 64.47015.6DL | R402H16 | 8853.06 | 7503.98 | 0 | YES |
| R4142 | R402H16 | 4K7R2F-GP | 64.47015.6DL | R402H16 | 8779.49 | 8019.6 | 180 | YES |
| R4143 | R402H16 | 4K7R2F-GP | 64.47015.6DL | R402H16 | 8893.06 | 7503.98 | 0 | YES |
| R4144 | R402H16 | 4K7R2F-GP | 64.47015.6DL | R402H16 | 8820.49 | 8019.6 | 180 | YES |
| R4145 | R402H16 | 4K7R2F-GP | 64.47015.6DL | R402H16 | 8934.06 | 7503.98 | 0 | YES |
| R4146 | R402H16 | 4K7R2F-GP | 64.47015.6DL | R402H16 | 8649.06 | 7503.98 | 0 | YES |
| R4149 | R402H16 | 4K7R2F-GP | 64.47015.6DL | R402H16 | 8699.06 | 7993.98 | 180 | YES |
| R4150 | R402H16 | 4K7R2F-GP | 64.47015.6DL | R402H16 | 13381.28 | 7278.67 | 180 | YES |
| R4151 | R402H16 | 4K7R2F-GP | 64.47015.6DL | R402H16 | 13141.28 | 6788.67 | 0 | YES |
| R4152 | R402H16 | 4K7R2F-GP | 64.47015.6DL | R402H16 | 13341.28 | 7278.67 | 180 | YES |
| R4154 | R402H16 | 4K7R2F-GP | 64.47015.6DL | R402H16 | 13255 | 7280 | 180 | YES |
| R4155 | R402H16 | 4K7R2F-GP | 64.47015.6DL | R402H16 | 13221.28 | 6788.67 | 0 | YES |
| R4156 | R402H16 | 4K7R2F-GP | 64.47015.6DL | R402H16 | 13261.28 | 6788.67 | 0 | YES |
| R4158 | R402H16 | 4K7R2F-GP | 64.47015.6DL | R402H16 | 13055 | 3920 | 180 | NO |
| R4159 | R402H16 | 4K7R2F-GP | 64.47015.6DL | R402H16 | 12785 | 3405 | 0 | NO |
| R4160 | R402H16 | 4K7R2F-GP | 64.47015.6DL | R402H16 | 13301.28 | 6788.67 | 0 | YES |
| R4161 | R402H16 | 4K7R2F-GP | 64.47015.6DL | R402H16 | 13381.28 | 6788.67 | 0 | YES |
| R4163 | R402H16 | 4K7R2F-GP | 64.47015.6DL | R402H16 | 13101.28 | 6788.67 | 0 | YES |
| R4164 | R402H16 | 4K7R2F-GP | 64.47015.6DL | R402H16 | 13015 | 3920 | 180 | NO |
| R4165 | R402H16 | 4K7R2F-GP | 64.47015.6DL | R402H16 | 13146.28 | 7278.67 | 180 | YES |
| R4166 | R402H16 | 4K7R2F-GP | 64.47015.6DL | R402H16 | 12825 | 3405 | 0 | NO |
| R4167 | R402H16 | 4K7R2F-GP | 64.47015.6DL | R402H16 | 12935 | 3920 | 180 | NO |
| R4168 | R402H16 | 4K7R2F-GP | 64.47015.6DL | R402H16 | 12865 | 3405 | 0 | NO |
| R4169 | R402H16 | 4K7R2F-GP | 64.47015.6DL | R402H16 | 12975 | 3920 | 180 | NO |
| R4170 | R402H16 | 4K7R2F-GP | 64.47015.6DL | R402H16 | 12905 | 3405 | 0 | NO |
| R4171 | R402H16 | 4K7R2F-GP | 64.47015.6DL | R402H16 | 12855 | 3920 | 180 | NO |
| R4172 | R402H16 | 4K7R2F-GP | 64.47015.6DL | R402H16 | 12945 | 3405 | 0 | NO |
| R4173 | R402H16 | 4K7R2F-GP | 64.47015.6DL | R402H16 | 12895 | 3920 | 180 | NO |
| R4174 | R402H16 | 4K7R2F-GP | 64.47015.6DL | R402H16 | 13025 | 3405 | 0 | NO |
| R4175 | R402H16 | 4K7R2F-GP | 64.47015.6DL | R402H16 | 12745 | 3405 | 0 | NO |
| R4176 | R402H16 | 4K7R2F-GP | 64.47015.6DL | R402H16 | 12985 | 3405 | 0 | NO |
| R4177 | R402H16 | 4K7R2F-GP | 64.47015.6DL | R402H16 | 9545 | 679 | 270 | YES |
| R4178 | R402H16 | 4K7R2F-GP | 64.47015.6DL | R402H16 | 12775 | 3995 | 180 | NO |
| R5200 | R402H16 | 0R2J-2-GP | 63.R0034.1DL | R402H16 | 4825.09 | 3340.41 | 270 | NO |
| R5201 | R402H16 | 0R2J-2-GP | 63.R0034.1DL | R402H16 | 4825.09 | 3390.41 | 270 | NO |
| R5202 | R402H16 | 1KR2J-1-GP | 63.10234.1DL | R402H16 | 4716.8100000000004 | 3082.12 | 0 | NO |
| R5762 | R402H16 | 1KR2F-3-GP | 64.10015.6DL | R402H16 | 2535 | 5275 | 0 | NO |
| R5763 | R402H16 | 1KR2F-3-GP | 64.10015.6DL | R402H16 | 2250 | 5365 | 0 | YES |
| R5764 | R402H16 | 5K6R2F-2-GP | 64.56015.6DL | R402H16 | 2580 | 5195 | 0 | NO |
| R5765 | R402H16 | 1K8R2F-GP | 64.18015.6DL | R402H16 | 2290 | 5275 | 0 | NO |
| R5766 | R402H16 | 1KR2F-3-GP | 64.10015.6DL | R402H16 | 2535 | 5195 | 180 | NO |
| R5767 | R402H16 | 1KR2F-3-GP | 64.10015.6DL | R402H16 | 2250 | 5275 | 180 | NO |
| R5768 | R402H16 | 1KR2F-3-GP | 64.10015.6DL | R402H16 | 2290 | 5200 | 180 | YES |
| R5769 | R402H16 | 1KR2F-3-GP | 64.10015.6DL | R402H16 | 2290 | 5201 | 180 | NO |
| R5770 | R402H16 | 1KR2F-3-GP | 64.10015.6DL | R402H16 | 2250 | 5200 | 0 | YES |
| R5771 | R402H16 | 1KR2F-3-GP | 64.10015.6DL | R402H16 | 2250 | 5275 | 180 | YES |
| R5772 | R402H16 | 1KR2F-3-GP | 64.10015.6DL | R402H16 | 3174 | 5425 | 270 | NO |
| R5774 | R1210H24 | 330R1210J-GP | 63.33137.1BL | R1210H24 | 8325 | 20 | 270 | NO |
| R7889 | R402H16 | 0R2J-2-GP | 63.R0034.1DL | R402H16 | 8241.18 | 493.79 | 180 | NO |
| R7892 | R402H16 | 0R2J-2-GP | 63.R0034.1DL | R402H16 | 8200.18 | 493.79 | 180 | NO |
| R7902 | R402H16 | 0R2J-2-GP | 63.R0034.1DL | R402H16 | 13590.11 | 1806.84 | 0 | NO |
| R7903 | R402H16 | 0R2J-2-GP | 63.R0034.1DL | R402H16 | 10530 | 222 | 270 | NO |
| R7904 | R402H16 | 0R2J-2-GP | 63.R0034.1DL | R402H16 | 10565 | 487 | 270 | NO |
| R7905 | R402H16 | 0R2J-2-GP | 63.R0034.1DL | R402H16 | 10351.16 | 335.63 | 270 | NO |
| R7906 | R402H16 | 0R2J-2-GP | 63.R0034.1DL | R402H16 | 13765.39 | 1692.35 | 90 | YES |
| R7907 | R402H16 | 0R2J-2-GP | 63.R0034.1DL | R402H16 | 8503 | 160 | 180 | NO |
| R7908 | R402H16 | 0R2J-2-GP | 63.R0034.1DL | R402H16 | 13649.18 | 1681.02 | 90 | NO |
| R7909 | R402H16 | 0R2J-2-GP | 63.R0034.1DL | R402H16 | 8992 | 634 | 180 | NO |
| R7910 | R402H16 | 0R2J-2-GP | 63.R0034.1DL | R402H16 | 8730 | 528 | 90 | NO |
| R7912 | R402H16 | 0R2J-2-GP | 63.R0034.1DL | R402H16 | 2744.06 | 7703.98 | 0 | NO |
| R7913 | R402H16 | 0R2J-2-GP | 63.R0034.1DL | R402H16 | 2784.06 | 7703.98 | 0 | NO |
| R7914 | R402H16 | 330R2J-3-GP | 63.33134.1DL | R402H16 | 12615 | 3920 | 0 | NO |
| R7915 | R402H16 | 0R2J-2-GP | 63.R0034.1DL | R402H16 | 4879.0600000000004 | 8223.98 | 0 | NO |
| R7916 | R402H16 | 0R2J-2-GP | 63.R0034.1DL | R402H16 | 4919.0600000000004 | 8223.98 | 0 | NO |
| R7917 | R402H16 | 0R2J-2-GP | 63.R0034.1DL | R402H16 | 10416.67 | 112.96 | 270 | NO |
| R7918 | R402H16 | 0R2J-2-GP | 63.R0034.1DL | R402H16 | 8574.06 | 7993.98 | 0 | NO |
| R7919 | R402H16 | 0R2J-2-GP | 63.R0034.1DL | R402H16 | 8614.06 | 7993.98 | 0 | NO |
| R7920 | R402H16 | 0R2J-2-GP | 63.R0034.1DL | R402H16 | 13021.28 | 7278.67 | 0 | NO |
| R7921 | R402H16 | 0R2J-2-GP | 63.R0034.1DL | R402H16 | 4959.0600000000004 | 7733.98 | 0 | NO |
| R7922 | R402H16 | 0R2J-2-GP | 63.R0034.1DL | R402H16 | 5119.0600000000004 | 7733.98 | 0 | NO |
| R7923 | R402H16 | 0R2J-2-GP | 63.R0034.1DL | R402H16 | 8654.06 | 7503.98 | 0 | NO |
| R7924 | R402H16 | 0R2J-2-GP | 63.R0034.1DL | R402H16 | 13101.28 | 6788.67 | 0 | NO |
| R7925 | R402H16 | 0R2J-2-GP | 63.R0034.1DL | R402H16 | 13261.28 | 6788.67 | 0 | NO |
| R7926 | R402H16 | 0R2J-2-GP | 63.R0034.1DL | R402H16 | 5329.06 | 8223.98 | 180 | NO |
| R7927 | R402H16 | 0R2J-2-GP | 63.R0034.1DL | R402H16 | 5166.79 | 8223.5 | 180 | NO |
| R7928 | R402H16 | 0R2J-2-GP | 63.R0034.1DL | R402H16 | 2984.06 | 7213.98 | 0 | NO |
| R7929 | R402H16 | 0R2J-2-GP | 63.R0034.1DL | R402H16 | 8814.06 | 7503.98 | 0 | NO |
| R7930 | R402H16 | 0R2J-2-GP | 63.R0034.1DL | R402H16 | 13381.28 | 7278.67 | 180 | NO |
| R7931 | R402H16 | 0R2J-2-GP | 63.R0034.1DL | R402H16 | 2991.48 | 7706.05 | 180 | NO |
| R7932 | R402H16 | 0R2J-2-GP | 63.R0034.1DL | R402H16 | 8984.06 | 7993.98 | 180 | NO |
| R7933 | R402H16 | 0R2J-2-GP | 63.R0034.1DL | R402H16 | 3154.06 | 7703.98 | 180 | NO |
| R7934 | R402H16 | 0R2J-2-GP | 63.R0034.1DL | R402H16 | 8820.49 | 8020 | 180 | NO |
| R7935 | R402H16 | 0R2J-2-GP | 63.R0034.1DL | R402H16 | 2824.06 | 7213.98 | 0 | NO |
| R7936 | R402H16 | 0R2J-2-GP | 63.R0034.1DL | R402H16 | 13141.28 | 6788.67 | 0 | NO |
| R7937 | R402H16 | 0R2J-2-GP | 63.R0034.1DL | R402H16 | 2864.06 | 7213.98 | 0 | NO |
| R7938 | R402H16 | 0R2J-2-GP | 63.R0034.1DL | R402H16 | 4999.0600000000004 | 7733.98 | 0 | NO |
| R7939 | R402H16 | 0R2J-2-GP | 63.R0034.1DL | R402H16 | 13301.28 | 6788.67 | 0 | NO |
| R7940 | R402H16 | 0R2J-2-GP | 63.R0034.1DL | R402H16 | 5289.06 | 8223.98 | 180 | NO |
| R7941 | R402H16 | 0R2J-2-GP | 63.R0034.1DL | R402H16 | 5125.79 | 8223.5 | 180 | NO |
| R7942 | R402H16 | 0R2J-2-GP | 63.R0034.1DL | R402H16 | 8854.06 | 7503.98 | 0 | NO |
| R7943 | R402H16 | 0R2J-2-GP | 63.R0034.1DL | R402H16 | 3024.06 | 7213.98 | 0 | NO |
| R7944 | R402H16 | 0R2J-2-GP | 63.R0034.1DL | R402H16 | 5159.0600000000004 | 7733.98 | 0 | NO |
| R7945 | R402H16 | 0R2J-2-GP | 63.R0034.1DL | R402H16 | 2950.79 | 7703.5 | 180 | NO |
| R7946 | R402H16 | 0R2J-2-GP | 63.R0034.1DL | R402H16 | 13341.28 | 7278.67 | 180 | NO |
| R7947 | R402H16 | 0R2J-2-GP | 63.R0034.1DL | R402H16 | 8944.06 | 7993.98 | 180 | NO |
| R7948 | R402H16 | 0R2J-2-GP | 63.R0034.1DL | R402H16 | 3114.06 | 7703.98 | 180 | NO |
| R7949 | R402H16 | 0R2J-2-GP | 63.R0034.1DL | R402H16 | 8779.49 | 8020 | 180 | NO |
| R7950 | R402H16 | 0R2J-2-GP | 63.R0034.1DL | R402H16 | 8694.06 | 7503.98 | 0 | NO |
| R7951 | R402H16 | 0R2J-2-GP | 63.R0034.1DL | R402H16 | 13181.28 | 6788.67 | 0 | NO |
| R7952 | R402H16 | 0R2J-2-GP | 63.R0034.1DL | R402H16 | 2904.06 | 7213.98 | 0 | NO |
| R7953 | R402H16 | 0R2J-2-GP | 63.R0034.1DL | R402H16 | 5039.0600000000004 | 7733.98 | 0 | NO |
| R7954 | R402H16 | 0R2J-2-GP | 63.R0034.1DL | R402H16 | 13341.28 | 6788.67 | 0 | NO |
| R7955 | R402H16 | 0R2J-2-GP | 63.R0034.1DL | R402H16 | 5085 | 8224 | 180 | NO |
| R7956 | R402H16 | 0R2J-2-GP | 63.R0034.1DL | R402H16 | 5249.06 | 8223.98 | 180 | NO |
| R7957 | R402H16 | 0R2J-2-GP | 63.R0034.1DL | R402H16 | 8894.06 | 7503.98 | 0 | NO |
| R7958 | R402H16 | 0R2J-2-GP | 63.R0034.1DL | R402H16 | 3064.06 | 7213.98 | 0 | NO |
| R7959 | R402H16 | 0R2J-2-GP | 63.R0034.1DL | R402H16 | 5199.0600000000004 | 7733.98 | 0 | NO |
| R7960 | R402H16 | 0R2J-2-GP | 63.R0034.1DL | R402H16 | 13301.28 | 7278.67 | 180 | NO |
| R7961 | R402H16 | 0R2J-2-GP | 63.R0034.1DL | R402H16 | 2910 | 7704 | 180 | NO |
| R7962 | R402H16 | 0R2J-2-GP | 63.R0034.1DL | R402H16 | 8904.06 | 7993.98 | 180 | NO |
| R7963 | R402H16 | 0R2J-2-GP | 63.R0034.1DL | R402H16 | 3074.06 | 7703.98 | 180 | NO |
| R7964 | R402H16 | 0R2J-2-GP | 63.R0034.1DL | R402H16 | 8738.5 | 7994 | 180 | NO |
| R7965 | R402H16 | 0R2J-2-GP | 63.R0034.1DL | R402H16 | 8734.06 | 7503.24 | 0 | NO |
| R7966 | R402H16 | 0R2J-2-GP | 63.R0034.1DL | R402H16 | 13061.28 | 7278.67 | 0 | NO |
| R7967 | R402H16 | 0R2J-2-GP | 63.R0034.1DL | R402H16 | 13221.28 | 6788.67 | 0 | NO |
| R7968 | R402H16 | 0R2J-2-GP | 63.R0034.1DL | R402H16 | 5079.0600000000004 | 7733.98 | 0 | NO |
| R7969 | R402H16 | 0R2J-2-GP | 63.R0034.1DL | R402H16 | 13381.28 | 6788.67 | 0 | NO |
| R7970 | R402H16 | 0R2J-2-GP | 63.R0034.1DL | R402H16 | 5044.0600000000004 | 8223.98 | 180 | NO |
| R7971 | R402H16 | 0R2J-2-GP | 63.R0034.1DL | R402H16 | 5209.0600000000004 | 8223.98 | 180 | NO |
| R7972 | R402H16 | 0R2J-2-GP | 63.R0034.1DL | R402H16 | 8934.06 | 7503.98 | 0 | NO |
| R7973 | R402H16 | 0R2J-2-GP | 63.R0034.1DL | R402H16 | 3104.06 | 7213.98 | 0 | NO |
| R7974 | R402H16 | 0R2J-2-GP | 63.R0034.1DL | R402H16 | 5239.0600000000004 | 7733.98 | 0 | NO |
| R7975 | R402H16 | 0R2J-2-GP | 63.R0034.1DL | R402H16 | 13261.28 | 7278.67 | 180 | NO |
| R7976 | R402H16 | 0R2J-2-GP | 63.R0034.1DL | R402H16 | 2865 | 7780 | 180 | NO |
| R7977 | R402H16 | 0R2J-2-GP | 63.R0034.1DL | R402H16 | 8862.76 | 8020.48 | 180 | NO |
| R7978 | R402H16 | 0R2J-2-GP | 63.R0034.1DL | R402H16 | 3040 | 7782 | 180 | NO |
| R7979 | R402H16 | 0R2J-2-GP | 63.R0034.1DL | R402H16 | 8697.56 | 7993.98 | 180 | NO |
| R7980 | R402H16 | 0R2J-2-GP | 63.R0034.1DL | R402H16 | 8774.06 | 7503.98 | 0 | NO |
| R7981 | R402H16 | 0R2J-2-GP | 63.R0034.1DL | R402H16 | 2944.06 | 7213.98 | 0 | NO |
| R7982 | R402H16 | 0R2J-2-GP | 63.R0034.1DL | R402H16 | 10230.6 | 20.239999999999998 | 270 | NO |
| R7990 | R402H16 | 0R2J-2-GP | 63.R0034.1DL | R402H16 | 12775 | 3920 | 180 | NO |
| R7998 | R402H16 | 330R2J-3-GP | 63.33134.1DL | R402H16 | 12655 | 3920 | 0 | NO |
| R7999 | R402H16 | 0R2J-2-GP | 63.R0034.1DL | R402H16 | 13146.28 | 7278.67 | 180 | NO |
| R8003 | R402H16 | 0R2J-2-GP | 63.R0034.1DL | R402H16 | 720 | 6080 | 0 | NO |
| R8005 | R402H16 | 0R2J-2-GP | 63.R0034.1DL | R402H16 | 760 | 6080 | 0 | NO |
| R8007 | R402H16 | 0R2J-2-GP | 63.R0034.1DL | R402H16 | 820 | 6065 | 90 | NO |
| R9020 | RL3115-4PH45 | D002RL3115F-L-GP | 64.R0025.L1L | RL3115-4PH45 | 1025 | 8170 | 180 | NO |
| R9023 | R402H16 | 22K6R2F-1-GP | 64.22625.6DL | R402H16 | 523 | 7649 | 180 | NO |
| R9024 | R402H16 | 191R2F-GP | 64.19105.6DL | R402H16 | 950 | 4724 | 270 | YES |
| R9025 | R402H14 | 100R2D-GP | 64.10006.6DL | R402H14 | 775 | 7232 | 90 | NO |
| R9026 | R402H14 | 100R2D-GP | 64.10006.6DL | R402H14 | 918 | 7214 | 180 | NO |
| R9027 | R402H16 | 63K4R2F-2-GP | 64.63425.6DL | R402H16 | 549 | 7708 | 270 | NO |
| R9028 | R402H16 | 43K2R2F-L-GP | 64.43225.6DL | R402H16 | 743 | 7644 | 180 | NO |
| R9029 | R402H16 | 4K7R2F-GP | 64.47015.6DL | R402H16 | 2905 | 7215 | 0 | YES |
| R9030 | R402H16 | 4K7R2F-GP | 64.47015.6DL | R402H16 | 5096 | 7732 | 0 | YES |
| R9031 | R402H16 | 4K7R2F-GP | 64.47015.6DL | R402H16 | 5281 | 7733 | 0 | NO |
| R9032 | R402H16 | 4K7R2F-GP | 64.47015.6DL | R402H16 | 8772 | 7503 | 0 | YES |
| R9033 | R402H16 | 4K7R2F-GP | 64.47015.6DL | R402H16 | 13224 | 6713 | 0 | NO |
| R9034 | R402H16 | 4K7R2F-GP | 64.47015.6DL | R402H16 | 3145 | 7215 | 0 | NO |
| R9035 | R402H16 | 4K7R2F-GP | 64.47015.6DL | R402H16 | 5428 | 8108 | 0 | YES |
| R9036 | R402H16 | 4K7R2F-GP | 64.47015.6DL | R402H16 | 5001 | 8224 | 180 | NO |
| R9037 | R402H16 | 4K7R2F-GP | 64.47015.6DL | R402H16 | 8976 | 7503 | 0 | NO |
| R9038 | R402H16 | 4K7R2F-GP | 64.47015.6DL | R402H16 | 13423 | 6785 | 0 | NO |
| R9039 | R402H16 | 4K7R2F-GP | 64.47015.6DL | R402H16 | 3033 | 7703 | 180 | NO |
| R9040 | R402H16 | 4K7R2F-GP | 64.47015.6DL | R402H16 | 2865 | 7705 | 180 | NO |
| R9041 | R402H16 | 4K7R2F-GP | 64.47015.6DL | R402H16 | 8881.7000000000007 | 8082.3 | 270 | NO |
| R9042 | R402H16 | 4K7R2F-GP | 64.47015.6DL | R402H16 | 8709 | 8071 | 180 | NO |
| R9043 | R402H16 | 4K7R2F-GP | 64.47015.6DL | R402H16 | 13261 | 7359 | 180 | NO |
| R9044 | R402H16 | 470R2F-GP | 64.47005.6DL | R402H16 | 1000.76 | 4324.3 | 0 | NO |
| R9045 | R402H16 | 470R2F-GP | 64.47005.6DL | R402H16 | 1000.79 | 4250.17 | 180 | NO |
| R9046 | R402H14 | 56R2F | 64.56R05.6D1 | R402H14 | 960.43 | 4324.43 | 180 | NO |
| R9047 | R402H14 | 56R2F | 64.56R05.6D1 | R402H14 | 960.46 | 4250.3 | 0 | NO |
| RJ1 | XRJH-01H-D-H71-D81-W | RJ45-LED-12P-10-GP | 22.10277.R91 | XRJH-01H-D-H71-D81-W | 615.83000000000004 | 1516.14 | 0 | NO |
| SC1114 | C402H22 | SCD1U16V2KX-3GP | 78.10421.2FL | C402H22 | 8582.52 | 160 | 0 | NO |
| SC1115 | C402H22 | SCD1U16V2KX-3GP | 78.10421.2FL | C402H22 | 8545 | 475 | 0 | NO |
| SC1116 | C402H22 | SCD1U16V2KX-3GP | 78.10421.2FL | C402H22 | 8617.52 | 160 | 0 | NO |
| SC1302 | C402H22 | SCD1U16V2KX-3GP | 78.10421.2FL | C402H22 | 10208.629999999999 | 173.98 | 90 | NO |
| SC1303 | C402H22 | SCD1U16V2KX-3GP | 78.10421.2FL | C402H22 | 3292.41 | 3269.3 | 180 | NO |
| SC1307 | C402H22 | SCD1U16V2KX-3GP | 78.10421.2FL | C402H22 | 5421.2 | 2168.0500000000002 | 180 | NO |
| SC1308 | C402H22 | SCD1U16V2KX-3GP | 78.10421.2FL | C402H22 | 1826 | 2894.72 | 270 | NO |
| SC1310 | C805H58 | SC10U6D3V5KX-4GP | 78.10620.21L | C805H58 | 3084.39 | 3262.01 | 90 | NO |
| SCN8 | A2541WV0-1QX4PA-6T | JWT-CON4-S24-GP | 21.61359.104 | A2541WV0-1QX4PA-6T | 1989 | 2743.72 | 0 | NO |
| SCN9 | A2541WV0-1QX4PA-6T | JWT-CON4-S24-GP | 21.61359.104 | A2541WV0-1QX4PA-6T | 5167.42 | 2155.94 | 180 | NO |
| SKT1 | 67643-3911 | SKT-USB-250-GP | 22.10254.181 | 67643-3911 | 1480.31 | 1428.74 | 0 | NO |
| SKT3 | SKT-SOIC16-153139H258 | SKT-SPI16P-GP-U | 62.10089.021 | SKT-SOIC16-153139H258 | 2537.31 | 2642.8 | 0 | NO |
| SKT4 | SKT-SOIC8-104117H235 | SKT-SPI8P-9-GP | 062.10029.0031 | SKT-SOIC8-104117H235 | 5270.26 | 2646.61 | 180 | NO |
| SKT5 | SKT-SOIC16-153139H258 | SKT-SPI16P-GP-U | 62.10089.021 | SKT-SOIC16-153139H258 | 3203.34 | 2642.11 | 0 | NO |
| SKT6 | SKT-SOIC8-104117H235 | SKT-SPI8P-9-GP | 062.10029.0031 | SKT-SOIC8-104117H235 | 1985.18 | 2256.06 | 0 | NO |
| SLED28 | LED1608AKH40 | LED-YG-51-GP | 83.01921.S70 | LED1608AKH40 | 7207.63 | -36.5 | 90 | NO |
| SLED29 | LED1608AKH40 | LED-YG-51-GP | 83.01921.S70 | LED1608AKH40 | 8489.34 | -18.149999999999999 | 270 | NO |
| SR707 | R402H16 | 150R2F-1-GP | 64.15005.6DL | R402H16 | 3019.29 | 3567.4 | 180 | NO |
| SR708 | R402H16 | 150R2F-1-GP | 64.15005.6DL | R402H16 | 4850 | 733.8 | 90 | NO |
| SR709 | R402H16 | 150R2F-1-GP | 64.15005.6DL | R402H16 | 4850 | 498.8 | 90 | NO |
| SR710 | R402H16 | 150R2F-1-GP | 64.15005.6DL | R402H16 | 4849.7 | 267.2 | 90 | NO |
| SR711 | R402H16 | 150R2F-1-GP | 64.15005.6DL | R402H16 | 4849.6000000000004 | 131.80000000000001 | 90 | NO |
| SR712 | R402H16 | 150R2F-1-GP | 64.15005.6DL | R402H16 | 13040 | 380 | 0 | NO |
| SR713 | R402H16 | 150R2F-1-GP | 64.15005.6DL | R402H16 | 13040 | 145 | 0 | NO |
| SR714 | R402H16 | 150R2F-1-GP | 64.15005.6DL | R402H16 | 13040 | 850 | 0 | NO |
| SR715 | R402H16 | 150R2F-1-GP | 64.15005.6DL | R402H16 | 13040 | 615 | 0 | NO |
| SR716 | R402H16 | 150R2F-1-GP | 64.15005.6DL | R402H16 | 7555 | 640 | 90 | NO |
| SR717 | R402H16 | 150R2F-1-GP | 64.15005.6DL | R402H16 | 10511 | 641 | 270 | NO |
| SR718 | R402H16 | 150R2F-1-GP | 64.15005.6DL | R402H16 | 7160 | 640 | 270 | NO |
| SR719 | R402H16 | 150R2F-1-GP | 64.15005.6DL | R402H16 | 7366.3 | 639.1 | 270 | NO |
| SR720 | R402H16 | 150R2F-1-GP | 64.15005.6DL | R402H16 | 9306 | 786 | 270 | NO |
| SR722 | R402H16 | 150R2F-1-GP | 64.15005.6DL | R402H16 | 10563.6 | 693.55 | 90 | NO |
| SR723 | R402H16 | 150R2F-1-GP | 64.15005.6DL | R402H16 | 10760 | 685 | 90 | NO |
| SR842 | R402H16 | 10KR2F-2-GP | 64.10025.6DL | R402H16 | 3552 | 3305 | 0 | NO |
| SR847 | R402H16 | 4K75R2F-1-GP | 64.47515.6DL | R402H16 | 1975 | 5725 | 180 | YES |
| SR849 | R402H16 | 4K75R2F-1-GP | 64.47515.6DL | R402H16 | 2015 | 5725 | 180 | YES |
| SR852 | R402H16 | 4K75R2F-1-GP | 64.47515.6DL | R402H16 | 2115 | 5505 | 90 | YES |
| SR853 | R402H16 | 4K75R2F-1-GP | 64.47515.6DL | R402H16 | 1975 | 5720.32 | 0 | NO |
| SR943 | R402H16 | 4K75R2F-1-GP | 64.47515.6DL | R402H16 | 2015 | 5720.32 | 0 | NO |
| SR944 | R402H16 | 4K75R2F-1-GP | 64.47515.6DL | R402H16 | 2115 | 5545 | 270 | NO |
| SR947 | R402H16 | 0R2J-2-GP | 63.R0034.1DL | R402H16 | 3348 | 3189 | 90 | NO |
| SR948 | R402H16 | 0R2J-2-GP | 63.R0034.1DL | R402H16 | 3457 | 3356 | 90 | NO |
| SR949 | R402H16 | 0R2J-2-GP | 63.R0034.1DL | R402H16 | 3366 | 3355 | 270 | NO |
| SR950 | R402H16 | 0R2J-2-GP | 63.R0034.1DL | R402H16 | 3463 | 3185 | 270 | NO |
| SW1 | DTS-63N-V | SW-TACT-4P-196-GP | 022.40001.0541 | DTS-63N-V | 13359.9 | 1705 | 0 | NO |
| SW5 | PTCFGP2-Q-TR | PUSH-SW132-GP | 62.40007.231 | PTCFGP2-Q-TR | 13011.2 | 1785.93 | 0 | NO |
| SW20 | LSSM12-P-V-TR | SW-SLIDE74-GP | 62.40018.451 | LSSM12-P-V-TR | 10411.08 | -91.25 | 0 | NO |
| TC10 | C805H54 | SC10U16V5KX-1-GP | 78.10621.81L | C805H54 | 1245 | 1955 | 270 | NO |
| TC11 | C805H54 | SC10U16V5KX-1-GP | 78.10621.81L | C805H54 | 1245 | 2035 | 270 | NO |
| TC12 | C805H54 | SC10U16V5KX-1-GP | 78.10621.81L | C805H54 | 1245 | 2115 | 270 | NO |
| TC14 | C1206-TO0D3H75 | SC22U25V6KX-GP-U | 078.22622.082N | C1206-TO0D3H75 | 1463.91 | 2559.8000000000002 | 90 | NO |
| TC15 | C1206-TO0D3H75 | SC22U25V6KX-GP-U | 078.22622.082N | C1206-TO0D3H75 | 1465.44 | 2435.23 | 90 | NO |
| TC17 | CT7343H83 | ST150U6D3VDM-28-GP | 077.51571.0001 | CT7343H83 | 1520 | 2045 | 90 | NO |
| TP71 | TPAD28 | TPAD28-2-GP | ZZ.PAD28.XXX | TPAD28 | 6601 | 3446 | 90 | NO |
| TP74 | TPAD28 | TPAD28-2-GP | ZZ.PAD28.XXX | TPAD28 | 6605 | 3721 | 90 | NO |
| TP75 | TPAD28 | TPAD28-2-GP | ZZ.PAD28.XXX | TPAD28 | 6605 | 3623 | 90 | NO |
| TP76 | TPAD28 | TPAD28-2-GP | ZZ.PAD28.XXX | TPAD28 | 6605 | 3671 | 90 | NO |
| TP77 | TPAD28 | TPAD28-2-GP | ZZ.PAD28.XXX | TPAD28 | 6320 | 3841 | 90 | NO |
| TP78 | TPAD28 | TPAD28-2-GP | ZZ.PAD28.XXX | TPAD28 | 6320 | 3291 | 90 | NO |
| TP80 | TPAD28 | TPAD28-2-GP | ZZ.PAD28.XXX | TPAD28 | 6420 | 3841 | 90 | NO |
| TP81 | TPAD28 | TPAD28-2-GP | ZZ.PAD28.XXX | TPAD28 | 6370 | 3841 | 90 | NO |
| TP92 | TPAD28 | TPAD28-2-GP | ZZ.PAD28.XXX | TPAD28 | 1750 | 4660 | 0 | NO |
| TP93 | TPAD28 | TPAD28-2-GP | ZZ.PAD28.XXX | TPAD28 | 1710 | 4680 | 0 | YES |
| TP94 | TPAD28 | TPAD28-2-GP | ZZ.PAD28.XXX | TPAD28 | 1773.77 | 4617.49 | 0 | NO |
| TP95 | TPAD28 | TPAD28-2-GP | ZZ.PAD28.XXX | TPAD28 | 1800 | 4660 | 0 | NO |
| TP96 | TPAD28 | TPAD28-2-GP | ZZ.PAD28.XXX | TPAD28 | 887 | 5249 | 0 | YES |
| TP97 | TPAD28 | TPAD28-2-GP | ZZ.PAD28.XXX | TPAD28 | 1690 | 4630 | 0 | YES |
| TP107 | TPAD28 | TPAD28-2-GP | ZZ.PAD28.XXX | TPAD28 | 1376 | 5013.38 | 0 | YES |
| TP120 | TPAD28 | TPAD28-2-GP | ZZ.PAD28.XXX | TPAD28 | 9236.2000000000007 | 1614.5 | 0 | YES |
| TP121 | TPAD28 | TPAD28-2-GP | ZZ.PAD28.XXX | TPAD28 | 9122 | 1123 | 0 | YES |
| TP122 | TPAD28 | TPAD28-2-GP | ZZ.PAD28.XXX | TPAD28 | 9208 | 1434 | 0 | YES |
| TP124 | TPAD28 | TPAD28-2-GP | ZZ.PAD28.XXX | TPAD28 | 9039.3700000000008 | 1456.66 | 270 | YES |
| TP134 | TPAD28 | TPAD28-2-GP | ZZ.PAD28.XXX | TPAD28 | 565 | 3729 | 90 | NO |
| TP135 | TPAD28 | TPAD28-2-GP | ZZ.PAD28.XXX | TPAD28 | 9275.59 | 1535.43 | 0 | YES |
| TP145 | TPAD28 | TPAD28-2-GP | ZZ.PAD28.XXX | TPAD28 | 1730 | 5525 | 0 | YES |
| TP147 | TPAD28 | TPAD28-2-GP | ZZ.PAD28.XXX | TPAD28 | 1625 | 2220 | 0 | NO |
| TP148 | TPAD28 | TPAD28-2-GP | ZZ.PAD28.XXX | TPAD28 | 901 | 2664 | 270 | NO |
| TP149 | TPAD28 | TPAD28-2-GP | ZZ.PAD28.XXX | TPAD28 | 833 | 2668 | 270 | NO |
| TP150 | TPAD28 | TPAD28-2-GP | ZZ.PAD28.XXX | TPAD28 | 758 | 2696 | 270 | NO |
| TP152 | TPAD28 | TPAD28-2-GP | ZZ.PAD28.XXX | TPAD28 | 460 | 2921 | 270 | NO |
| TP153 | TPAD28 | TPAD28-2-GP | ZZ.PAD28.XXX | TPAD28 | 1575 | 4680 | 0 | YES |
| TP154 | TPAD28 | TPAD28-2-GP | ZZ.PAD28.XXX | TPAD28 | 1921.73 | 4660.75 | 0 | NO |
| TP155 | TPAD28 | TPAD28-2-GP | ZZ.PAD28.XXX | TPAD28 | 1820 | 4660 | 0 | YES |
| TP156 | TPAD28 | TPAD28-2-GP | ZZ.PAD28.XXX | TPAD28 | 1642.22 | 4579.1899999999996 | 0 | NO |
| TP157 | TPAD28 | TPAD28-2-GP | ZZ.PAD28.XXX | TPAD28 | 458.82 | 2871.41 | 270 | NO |
| TP158 | TPAD28 | TPAD28-2-GP | ZZ.PAD28.XXX | TPAD28 | 913 | 3316 | 270 | NO |
| TP159 | TPAD28 | TPAD28-2-GP | ZZ.PAD28.XXX | TPAD28 | 1685.99 | 5272.21 | 0 | YES |
| TP160 | TPAD28 | TPAD28-2-GP | ZZ.PAD28.XXX | TPAD28 | 2030 | 5345 | 0 | NO |
| TP161 | TPAD28 | TPAD28-2-GP | ZZ.PAD28.XXX | TPAD28 | 1980 | 5295 | 0 | NO |
| TP162 | TPAD28 | TPAD28-2-GP | ZZ.PAD28.XXX | TPAD28 | 1980 | 5345 | 0 | NO |
| TP163 | TPAD28 | TPAD28-2-GP | ZZ.PAD28.XXX | TPAD28 | 629 | 3223 | 270 | NO |
| TP164 | TPAD28 | TPAD28-2-GP | ZZ.PAD28.XXX | TPAD28 | 9551.18 | 1417.32 | 90 | YES |
| TP165 | TPAD28 | TPAD28-2-GP | ZZ.PAD28.XXX | TPAD28 | 1040 | 2862 | 270 | NO |
| TP166 | TPAD32 | TPAD32-GP | ZZ.0TPAD.191 | TPAD32 | 2235 | 6015 | 90 | NO |
| TP167 | TPAD28 | TPAD28-2-GP | ZZ.PAD28.XXX | TPAD28 | 13195 | 7315 | 0 | NO |
| TP169 | TPAD28 | TPAD28-2-GP | ZZ.PAD28.XXX | TPAD28 | 13195 | 7370 | 0 | NO |
| TP170 | TPAD28 | TPAD28-2-GP | ZZ.PAD28.XXX | TPAD28 | 947 | 3356 | 270 | NO |
| TP171 | TPAD32 | TPAD32-GP | ZZ.0TPAD.191 | TPAD32 | 9065 | 3165 | 0 | NO |
| TP172 | TPAD28 | TPAD28-2-GP | ZZ.PAD28.XXX | TPAD28 | 2047 | 4798.04 | 0 | NO |
| TP173 | TPAD28 | TPAD28-2-GP | ZZ.PAD28.XXX | TPAD28 | 1998.29 | 4859.47 | 0 | NO |
| TP177 | TPAD28 | TPAD28-2-GP | ZZ.PAD28.XXX | TPAD28 | 1982.79 | 4962.3 | 0 | NO |
| TP178 | TPAD28 | TPAD28-2-GP | ZZ.PAD28.XXX | TPAD28 | 2045 | 4900 | 0 | NO |
| TP179 | TPAD28 | TPAD28-2-GP | ZZ.PAD28.XXX | TPAD28 | 1998.8 | 4981.49 | 0 | YES |
| TP180 | TPAD28 | TPAD28-2-GP | ZZ.PAD28.XXX | TPAD28 | 1980 | 4935 | 0 | YES |
| TP181 | TPAD28 | TPAD28-2-GP | ZZ.PAD28.XXX | TPAD28 | 664.94 | 5569.16 | 0 | NO |
| TP184 | TPAD28 | TPAD28-2-GP | ZZ.PAD28.XXX | TPAD28 | 13195 | 7260 | 0 | NO |
| TP190 | TPAD28 | TPAD28-2-GP | ZZ.PAD28.XXX | TPAD28 | 9605 | 1000 | 90 | YES |
| TP191 | TPAD28 | TPAD28-2-GP | ZZ.PAD28.XXX | TPAD28 | 1658.64 | 5339.33 | 0 | YES |
| TP192 | TPAD28 | TPAD28-2-GP | ZZ.PAD28.XXX | TPAD28 | 9511.81 | 1535.43 | 90 | YES |
| TP193 | TPAD28 | TPAD28-2-GP | ZZ.PAD28.XXX | TPAD28 | 9470 | 715 | 0 | YES |
| TP194 | TPAD28 | TPAD28-2-GP | ZZ.PAD28.XXX | TPAD28 | 9443 | 985 | 90 | YES |
| TP196 | TPAD28 | TPAD28-2-GP | ZZ.PAD28.XXX | TPAD28 | 9530 | 1045 | 90 | YES |
| TP197 | TPAD28 | TPAD28-2-GP | ZZ.PAD28.XXX | TPAD28 | 9605 | 1050 | 90 | YES |
| TP198 | TPAD28 | TPAD28-2-GP | ZZ.PAD28.XXX | TPAD28 | 9157.5 | 1339 | 180 | YES |
| TP199 | TPAD28 | TPAD28-2-GP | ZZ.PAD28.XXX | TPAD28 | 9196.5 | 1378 | 180 | YES |
| TP200 | TPAD28 | TPAD28-2-GP | ZZ.PAD28.XXX | TPAD28 | 9197 | 1575 | 0 | YES |
| TP201 | TPAD28 | TPAD28-2-GP | ZZ.PAD28.XXX | TPAD28 | 9157.5 | 1535 | 270 | YES |
| TP202 | TPAD28 | TPAD28-2-GP | ZZ.PAD28.XXX | TPAD28 | 9157.5 | 1456.5 | 90 | YES |
| TP203 | TPAD28 | TPAD28-2-GP | ZZ.PAD28.XXX | TPAD28 | 9196.85 | 1496.06 | 90 | YES |
| TP204 | TPAD28 | TPAD28-2-GP | ZZ.PAD28.XXX | TPAD28 | 9157.9 | 1614.2 | 270 | YES |
| TP205 | TPAD28 | TPAD28-2-GP | ZZ.PAD28.XXX | TPAD28 | 9118 | 1417.5 | 90 | YES |
| TP206 | TPAD28 | TPAD28-2-GP | ZZ.PAD28.XXX | TPAD28 | 9787.4 | 1614.17 | 180 | YES |
| TP207 | TPAD28 | TPAD28-2-GP | ZZ.PAD28.XXX | TPAD28 | 9386 | 995 | 90 | YES |
| TP208 | TPAD28 | TPAD28-2-GP | ZZ.PAD28.XXX | TPAD28 | 9826.77 | 1338.58 | 270 | YES |
| TP209 | TPAD28 | TPAD28-2-GP | ZZ.PAD28.XXX | TPAD28 | 9826.32 | 1574.8 | 270 | YES |
| TP210 | TPAD28 | TPAD28-2-GP | ZZ.PAD28.XXX | TPAD28 | 9590.5499999999993 | 1456.69 | 0 | YES |
| TP211 | TPAD28 | TPAD28-2-GP | ZZ.PAD28.XXX | TPAD28 | 9529 | 989 | 0 | YES |
| TP213 | TPAD28 | TPAD28-2-GP | ZZ.PAD28.XXX | TPAD28 | 8660 | 825 | 90 | YES |
| TP214 | TPAD28 | TPAD28-2-GP | ZZ.PAD28.XXX | TPAD28 | 9118.2000000000007 | 1575 | 90 | YES |
| TP215 | TPAD28 | TPAD28-2-GP | ZZ.PAD28.XXX | TPAD28 | 9118.17 | 1496.17 | 90 | YES |
| TP216 | TPAD28 | TPAD28-2-GP | ZZ.PAD28.XXX | TPAD28 | 1770 | 4660 | 0 | YES |
| TP217 | TPAD28 | TPAD28-2-GP | ZZ.PAD28.XXX | TPAD28 | 1795.99 | 4574.79 | 0 | NO |
| TP218 | TPAD28 | TPAD28-2-GP | ZZ.PAD28.XXX | TPAD28 | 1701.92 | 4657.76 | 0 | NO |
| TP219 | TPAD28 | TPAD28-2-GP | ZZ.PAD28.XXX | TPAD28 | 1980 | 5230 | 0 | NO |
| TP220 | TPAD28 | TPAD28-2-GP | ZZ.PAD28.XXX | TPAD28 | 1395 | 4665 | 270 | YES |
| TP221 | TPAD28 | TPAD28-2-GP | ZZ.PAD28.XXX | TPAD28 | 1177.71 | 4998.96 | 0 | YES |
| TP222 | TPAD28 | TPAD28-2-GP | ZZ.PAD28.XXX | TPAD28 | 9590.5499999999993 | 1299.21 | 0 | YES |
| TP226 | TPAD28 | TPAD28-2-GP | ZZ.PAD28.XXX | TPAD28 | 1345 | 4660 | 0 | YES |
| TP227 | TPAD28 | TPAD28-2-GP | ZZ.PAD28.XXX | TPAD28 | 1340.9 | 4657.8 | 0 | NO |
| TP228 | TPAD28 | TPAD28-2-GP | ZZ.PAD28.XXX | TPAD28 | 1780 | 5470 | 0 | YES |
| TP229 | TPAD28 | TPAD28-2-GP | ZZ.PAD28.XXX | TPAD28 | 1730 | 5425 | 0 | YES |
| TP230 | TPAD28 | TPAD28-2-GP | ZZ.PAD28.XXX | TPAD28 | 1765 | 5715 | 0 | NO |
| TP231 | TPAD28 | TPAD28-2-GP | ZZ.PAD28.XXX | TPAD28 | 1670 | 5455 | 0 | YES |
| TP232 | TPAD28 | TPAD28-2-GP | ZZ.PAD28.XXX | TPAD28 | 1745 | 5615 | 0 | NO |
| TP233 | TPAD28 | TPAD28-2-GP | ZZ.PAD28.XXX | TPAD28 | 1389.3 | 4656.6000000000004 | 0 | NO |
| TP234 | TPAD28 | TPAD28-2-GP | ZZ.PAD28.XXX | TPAD28 | 9925.4 | 186.75 | 180 | NO |
| TP236 | TPAD28 | TPAD28-2-GP | ZZ.PAD28.XXX | TPAD28 | 1020 | 4977 | 0 | NO |
| TP237 | TPAD28 | TPAD28-2-GP | ZZ.PAD28.XXX | TPAD28 | 1785 | 5763.76 | 0 | NO |
| TP238 | TPAD28 | TPAD28-2-GP | ZZ.PAD28.XXX | TPAD28 | 9629.92 | 1574.8 | 270 | YES |
| TP239 | TPAD28 | TPAD28-2-GP | ZZ.PAD28.XXX | TPAD28 | 9590.5499999999993 | 1535.43 | 270 | YES |
| TP240 | TPAD28 | TPAD28-2-GP | ZZ.PAD28.XXX | TPAD28 | 1745 | 5665 | 0 | NO |
| TP241 | TPAD28 | TPAD28-2-GP | ZZ.PAD28.XXX | TPAD28 | 1415 | 4614 | 90 | NO |
| TP242 | TPAD28 | TPAD28-2-GP | ZZ.PAD28.XXX | TPAD28 | 1205 | 4610 | 0 | NO |
| TP243 | TPAD28 | TPAD28-2-GP | ZZ.PAD28.XXX | TPAD28 | 1255 | 4660 | 0 | NO |
| TP244 | TPAD28 | TPAD28-2-GP | ZZ.PAD28.XXX | TPAD28 | 1285 | 4560 | 0 | NO |
| TP245 | TPAD28 | TPAD28-2-GP | ZZ.PAD28.XXX | TPAD28 | 1362.72 | 4964.78 | 0 | YES |
| TP262 | TPAD28 | TPAD28-2-GP | ZZ.PAD28.XXX | TPAD28 | 9590.5499999999993 | 1377.95 | 270 | YES |
| TP263 | TPAD28 | TPAD28-2-GP | ZZ.PAD28.XXX | TPAD28 | 9497 | 1129 | 0 | YES |
| TP264 | TPAD28 | TPAD28-2-GP | ZZ.PAD28.XXX | TPAD28 | 9590.5499999999993 | 1614.17 | 90 | YES |
| TP265 | TPAD28 | TPAD28-2-GP | ZZ.PAD28.XXX | TPAD28 | 9551.18 | 1496.06 | 0 | YES |
| TP266 | TPAD28 | TPAD28-2-GP | ZZ.PAD28.XXX | TPAD28 | 1020.32 | 4752.74 | 270 | NO |
| TP267 | TPAD28 | TPAD28-2-GP | ZZ.PAD28.XXX | TPAD28 | 8613.1 | 1226.08 | 0 | NO |
| TP268 | TPAD28 | TPAD28-2-GP | ZZ.PAD28.XXX | TPAD28 | 9039.7000000000007 | 1574.78 | 0 | YES |
| TP269 | TPAD28 | TPAD28-2-GP | ZZ.PAD28.XXX | TPAD28 | 2085 | 5635 | 0 | NO |
| TP270 | TPAD28 | TPAD28-2-GP | ZZ.PAD28.XXX | TPAD28 | 1317.18 | 4986.82 | 0 | YES |
| TP273 | TPAD28 | TPAD28-2-GP | ZZ.PAD28.XXX | TPAD28 | 1057.28 | 4716.28 | 270 | YES |
| TP274 | TPAD28 | TPAD28-2-GP | ZZ.PAD28.XXX | TPAD28 | 9039.2000000000007 | 1377.8 | 0 | YES |
| TP277 | TPAD28 | TPAD28-2-GP | ZZ.PAD28.XXX | TPAD28 | 8467.2999999999993 | 1231.28 | 0 | NO |
| TP278 | TPAD28 | TPAD28-2-GP | ZZ.PAD28.XXX | TPAD28 | 9080.2000000000007 | 1533.4 | 270 | YES |
| TP279 | TPAD28 | TPAD28-2-GP | ZZ.PAD28.XXX | TPAD28 | 9905.51 | 1338.58 | 270 | YES |
| TP280 | TPAD28 | TPAD28-2-GP | ZZ.PAD28.XXX | TPAD28 | 9826.77 | 1417.32 | 270 | YES |
| TP281 | TPAD28 | TPAD28-2-GP | ZZ.PAD28.XXX | TPAD28 | 9787.4 | 1535.43 | 270 | YES |
| TP282 | TPAD28 | TPAD28-2-GP | ZZ.PAD28.XXX | TPAD28 | 9708.66 | 1456.69 | 0 | YES |
| TP283 | TPAD28 | TPAD28-2-GP | ZZ.PAD28.XXX | TPAD28 | 9669.2900000000009 | 1338.58 | 0 | YES |
| TP284 | TPAD28 | TPAD28-2-GP | ZZ.PAD28.XXX | TPAD28 | 9672.6299999999992 | 1000 | 0 | YES |
| TP285 | TPAD28 | TPAD28-2-GP | ZZ.PAD28.XXX | TPAD28 | 9672.6299999999992 | 1050 | 0 | YES |
| TP286 | TPAD28 | TPAD28-2-GP | ZZ.PAD28.XXX | TPAD28 | 9820 | 1050 | 270 | YES |
| TP287 | TPAD28 | TPAD28-2-GP | ZZ.PAD28.XXX | TPAD28 | 9820 | 1000 | 270 | YES |
| TP288 | TPAD28 | TPAD28-2-GP | ZZ.PAD28.XXX | TPAD28 | 9708.66 | 1614.17 | 270 | YES |
| TP289 | TPAD28 | TPAD28-2-GP | ZZ.PAD28.XXX | TPAD28 | 9748.0300000000007 | 1574.8 | 0 | YES |
| TP290 | TPAD28 | TPAD28-2-GP | ZZ.PAD28.XXX | TPAD28 | 9748.0300000000007 | 1417.32 | 0 | YES |
| TP291 | TPAD28 | TPAD28-2-GP | ZZ.PAD28.XXX | TPAD28 | 10314 | 1125 | 0 | NO |
| TP292 | TPAD28 | TPAD28-2-GP | ZZ.PAD28.XXX | TPAD28 | 1587.9 | 4584.5 | 270 | NO |
| TP293 | TPAD28 | TPAD28-2-GP | ZZ.PAD28.XXX | TPAD28 | 1603 | 4659 | 0 | NO |
| TP294 | TPAD28 | TPAD28-2-GP | ZZ.PAD28.XXX | TPAD28 | 9708.66 | 1377.95 | 0 | YES |
| TP295 | TPAD28 | TPAD28-2-GP | ZZ.PAD28.XXX | TPAD28 | 1642.68 | 4629.83 | 0 | NO |
| TP296 | TPAD28 | TPAD28-2-GP | ZZ.PAD28.XXX | TPAD28 | 1650 | 4680 | 0 | YES |
| TP297 | TPAD28 | TPAD28-2-GP | ZZ.PAD28.XXX | TPAD28 | 9827 | 1496 | 270 | YES |
| TP298 | TPAD28 | TPAD28-2-GP | ZZ.PAD28.XXX | TPAD28 | 1690 | 4580 | 0 | YES |
| TP299 | TPAD28 | TPAD28-2-GP | ZZ.PAD28.XXX | TPAD28 | 9748.0300000000007 | 1338.58 | 0 | YES |
| TP300 | TPAD28 | TPAD28-2-GP | ZZ.PAD28.XXX | TPAD28 | 9708.66 | 1535.43 | 270 | YES |
| TP301 | TPAD28 | TPAD28-2-GP | ZZ.PAD28.XXX | TPAD28 | 12780 | 3855 | 0 | NO |
| TP302 | TPAD28 | TPAD28-2-GP | ZZ.PAD28.XXX | TPAD28 | 1683.2 | 4552.78 | 0 | NO |
| TP303 | TPAD28 | TPAD28-2-GP | ZZ.PAD28.XXX | TPAD28 | 9750.0400000000009 | 1000.97 | 90 | YES |
| TP304 | TPAD28 | TPAD28-2-GP | ZZ.PAD28.XXX | TPAD28 | 9750.0400000000009 | 1050.97 | 90 | YES |
| TP305 | TPAD28 | TPAD28-2-GP | ZZ.PAD28.XXX | TPAD28 | 1206.8 | 4660.2 | 0 | NO |
| TP306 | TPAD28 | TPAD28-2-GP | ZZ.PAD28.XXX | TPAD28 | 1284.5 | 4814.7 | 0 | YES |
| TP307 | TPAD28 | TPAD28-2-GP | ZZ.PAD28.XXX | TPAD28 | 1282.8 | 4761.2 | 0 | YES |
| TP308 | TPAD28 | TPAD28-2-GP | ZZ.PAD28.XXX | TPAD28 | 1276.33 | 4417.05 | 0 | NO |
| TP309 | TPAD28 | TPAD28-2-GP | ZZ.PAD28.XXX | TPAD28 | 8948.5 | 1120.5999999999999 | 0 | YES |
| TP310 | TPAD28 | TPAD28-2-GP | ZZ.PAD28.XXX | TPAD28 | 9669.2900000000009 | 1496.06 | 0 | YES |
| TP311 | TPAD28 | TPAD28-2-GP | ZZ.PAD28.XXX | TPAD28 | 8545.1 | 1226.4000000000001 | 0 | NO |
| TP317 | TPAD28 | TPAD28-2-GP | ZZ.PAD28.XXX | TPAD28 | 1736.18 | 5168.8100000000004 | 0 | YES |
| TP318 | TPAD28 | TPAD28-2-GP | ZZ.PAD28.XXX | TPAD28 | 1818.11 | 5249.78 | 0 | YES |
| TP319 | TPAD28 | TPAD28-2-GP | ZZ.PAD28.XXX | TPAD28 | 1780 | 5420 | 0 | YES |
| TP320 | TPAD28 | TPAD28-2-GP | ZZ.PAD28.XXX | TPAD28 | 1936.1 | 5788.8 | 0 | NO |
| TP321 | TPAD28 | TPAD28-2-GP | ZZ.PAD28.XXX | TPAD28 | 1730 | 5475 | 0 | YES |
| TP324 | TPAD28 | TPAD28-2-GP | ZZ.PAD28.XXX | TPAD28 | 1575 | 4580 | 0 | YES |
| TP325 | TPAD28 | TPAD28-2-GP | ZZ.PAD28.XXX | TPAD28 | 1547 | 4611 | 0 | NO |
| TP326 | TPAD28 | TPAD28-2-GP | ZZ.PAD28.XXX | TPAD28 | 1545 | 4660 | 0 | NO |
| TP327 | TPAD28 | TPAD28-2-GP | ZZ.PAD28.XXX | TPAD28 | 1575 | 4630 | 0 | YES |
| TP328 | TPAD28 | TPAD28-2-GP | ZZ.PAD28.XXX | TPAD28 | 8355 | 1005 | 270 | NO |
| TP800 | TPAD28 | TPAD28-2-GP | ZZ.PAD28.XXX | TPAD28 | 4818.01 | 3290.85 | 90 | NO |
| U1 | BGA1311C37D5H134 | PM8546A-FEIP-GP | 071.08546.000U | BGA1311C37D5H134 | 9472.44 | 1889.76 | 270 | NO |
| U2 | QFN32-G3D45-UH32 | ADM1278-2ACPZ-RL-1-GP | 074.01278.0A7Z | QFN32-G3D45-UH32 | 543 | 7349 | 0 | NO |
| U4 | QSOIC16H69 | MAX6654MEE-2-GP | 074.06654.00BS | QSOIC16H69 | 10060.030000000001 | 240.07 | 180 | NO |
| U6 | TVSOP24H48 | SNLVC8T245DGVR-GP | 73.8T245.B29 | TVSOP24H48 | 8402.52 | 405 | 180 | NO |
| U8 | SOT-363H44 | 2N7002DW-7F-GP | 84.27002.C3F | SOT-363H44 | 405 | 4750 | 180 | NO |
| U9 | SOIC8-1H86 | N25Q128A11ESE40F-GP | 072.25128.0A01 | SOIC8-1H86 | 5270.26 | 2647.61 | 0 | NO |
| U10 | SOIC8H69 | CAT24C128WI-GT3-GP | 72.24128.J01 | SOIC8H69 | 8850 | 385 | 270 | NO |
| U12 | SOT-363H44 | 2N7002DW-7F-GP | 84.27002.C3F | SOT-363H44 | 555 | 4925 | 0 | NO |
| U13 | SOT-363H44 | 2N7002DW-7F-GP | 84.27002.C3F | SOT-363H44 | 2434 | 4646 | 0 | YES |
| U15 | SOT23-8PH58 | TMP421AIDCNRG4-GP | 74.04214.079 | SOT23-8PH58 | 10203.790000000001 | 272.7 | 90 | YES |
| U16 | SOIC8H69 | 24LC64-I-SN-GP | 72.02464.A01 | SOIC8H69 | 2734.88 | 5856.65 | 90 | NO |
| U18 | BGA96D075133H48 | K4B2G1646F-BCK0-GP-U | 072.4B216.0A0U | BGA96D075133H48 | 1408.19 | 6062.2 | 270 | NO |
| U19 | SOIC16-6H105 | MX25L25635FMI-10G-GP | 72.25635.A01 | SOIC16-6H105 | 2537.31 | 2642.8 | 180 | NO |
| U20 | QFN64G9-G3D6H40 | WGI210AT-2-GP | 071.210AT.0003 | QFN64G9-G3D6H40 | 715 | 2979 | 270 | NO |
| U21 | SOIC8H69 | ICS551MLFT-GP | 71.00551.00A | SOIC8H69 | 423.66 | 3743.07 | 0 | NO |
| U22 | SOT-6H58 | AZC099-04S-1-GP | 75.09904.07C | SOT-6H58 | 1493.8 | 1758.31 | 180 | NO |
| U23 | SOT-363H44 | 2N7002DW-7F-GP | 84.27002.C3F | SOT-363H44 | 2691 | 4763 | 0 | NO |
| U24 | SSOIC8-2H44 | PCA9511ADP-T-GP | 71.P9511.00W | SSOIC8-2H44 | 4782 | 3783 | 90 | NO |
| U25 | SC70-5H44 | SN74LVC1G07DCKRG4-2-GP | 73.01G07.01H | SC70-5H44 | 742.69 | 5962.2 | 0 | NO |
| U27 | MSOP10H44 | TS5A23157DGSR-GP | 74.23157.A99 | MSOP10H44 | 8810 | 25 | 270 | NO |
| U28 | SOT-363H44 | 2N7002DW-7F-GP | 84.27002.C3F | SOT-363H44 | 2539 | 4306 | 90 | NO |
| U29 | SSOIC8-2H44 | PCA9511ADP-T-GP | 71.P9511.00W | SSOIC8-2H44 | 1692 | 7384 | 90 | NO |
| U30 | SSOIC8-2H44 | PCA9511ADP-T-GP | 71.P9511.00W | SSOIC8-2H44 | 1620 | 7935 | 90 | NO |
| U31 | SSOIC8-2H44 | PCA9511ADP-T-GP | 71.P9511.00W | SSOIC8-2H44 | 2015 | 7700 | 90 | NO |
| U32 | SOT-363H44 | 2N7002DW-7F-GP | 84.27002.C3F | SOT-363H44 | 2116.38 | 4338.45 | 270 | YES |
| U33 | SSOIC8-2H44 | PCA9511ADP-T-GP | 71.P9511.00W | SSOIC8-2H44 | 2015 | 7145 | 90 | NO |
| U34 | SSOIC8-2H44 | PCA9511ADP-T-GP | 71.P9511.00W | SSOIC8-2H44 | 1219 | 7298 | 180 | NO |
| U35 | SC70-5H44 | SN74LVC1G07DCKRG4-2-GP | 73.01G07.01H | SC70-5H44 | 895 | 6320 | 180 | NO |
| U36 | SOIC16-6H105 | MX25L25635FMI-10G-GP | 72.25635.A01 | SOIC16-6H105 | 3203.34 | 2642.11 | 180 | NO |
| U37 | SOT-363H44 | 2N7002DW-7F-GP | 84.27002.C3F | SOT-363H44 | 2116.38 | 4338.45 | 90 | NO |
| U38 | SC70-5H44 | SN74LVC1G08DCKR-GP | 73.01G08.L03 | SC70-5H44 | 7465 | 312 | 270 | NO |
| U39 | SOT-363H44 | 2N7002DW-7F-GP | 84.27002.C3F | SOT-363H44 | 1913 | 4116 | 90 | YES |
| U40 | BGA408D19H52 | AST2400A1-GP | 71.24001.00U | BGA408D19H52 | 1500.19 | 5137.2 | 180 | NO |
| U41 | SOIC8H69 | LM393ADR-1-GP | 74.00393.I21 | SOIC8H69 | 2832.29 | 3361.4 | 270 | NO |
| U42 | SC70-5H44 | SN74LVC1G07DCKRG4-2-GP | 73.01G07.01H | SC70-5H44 | 1048.08 | 4022.92 | 0 | NO |
| U43 | SOIC8H69 | PCF8563T-1-GP | 71.08563.A0A | SOIC8H69 | 5039.09 | 3315.41 | 90 | NO |
| U44 | SOIC8-1H86 | W25Q80DVSSIG-1-GP | 072.25Q80.0A01 | SOIC8-1H86 | 1985.18 | 2256.06 | 180 | NO |
| U45 | SC70-6H44 | SN74AUP1T97DCKR-GP | 73.01T97.02J | SC70-6H44 | 2727 | 4988 | 270 | NO |
| U47 | SC70-5H44 | SN74LVC1G08DCKR-GP | 73.01G08.L03 | SC70-5H44 | 13741.74 | 1789.95 | 180 | YES |
| U49 | SC70-6H44 | SN74AUP1T97DCKR-GP | 73.01T97.02J | SC70-6H44 | 2727 | 5110 | 90 | NO |
| U50 | QFN16G3540-G215265H40 | SN74CBTLV3257RGYR-1-GP | 73.03257.003 | QFN16G3540-G215265H40 | 1430 | 3880 | 90 | NO |
| U52 | SC70-5H44 | SN74LVC1G07DCKRG4-2-GP | 73.01G07.01H | SC70-5H44 | 2935.62 | 4869 | 0 | NO |
| U53 | SC70-5H44 | SN74LVC1G07DCKRG4-2-GP | 73.01G07.01H | SC70-5H44 | 2942.62 | 4728 | 270 | NO |
| U54 | TSOIC16H48 | TCA9554PWR-GP | 71.09554.B0W | TSOIC16H48 | 4704 | 957 | 0 | NO |
| U55 | TSOIC16H48 | TCA9554PWR-GP | 71.09554.B0W | TSOIC16H48 | 7876.38 | 1205 | 270 | NO |
| U56 | TSOIC16H48 | TCA9554PWR-GP | 71.09554.B0W | TSOIC16H48 | 7847.38 | 891 | 270 | NO |
| U64 | SC70-5H44 | SN74LVC1G08DCKR-GP | 73.01G08.L03 | SC70-5H44 | 2930 | 7465 | 0 | YES |
| U65 | SC70-5H44 | SN74LVC1G08DCKR-GP | 73.01G08.L03 | SC70-5H44 | 5060 | 7985 | 0 | YES |
| U66 | SC70-5H44 | SN74LVC1G08DCKR-GP | 73.01G08.L03 | SC70-5H44 | 5220 | 7985 | 0 | YES |
| U67 | SC70-5H44 | SN74LVC1G08DCKR-GP | 73.01G08.L03 | SC70-5H44 | 8655 | 7755 | 0 | YES |
| U68 | SC70-5H44 | SN74LVC1G08DCKR-GP | 73.01G08.L03 | SC70-5H44 | 13102.22 | 7034.69 | 0 | YES |
| U69 | SC70-5H44 | SN74LVC1G08DCKR-GP | 73.01G08.L03 | SC70-5H44 | 3090 | 7465 | 0 | YES |
| U70 | SC70-5H44 | SN74LVC1G08DCKR-GP | 73.01G08.L03 | SC70-5H44 | 5380 | 7985 | 0 | YES |
| U71 | SC70-5H44 | SN74LVC1G08DCKR-GP | 73.01G08.L03 | SC70-5H44 | 4892.22 | 7984.69 | 0 | YES |
| U72 | SC70-5H44 | SN74LVC1G08DCKR-GP | 73.01G08.L03 | SC70-5H44 | 8795 | 7755 | 0 | YES |
| U73 | SC70-5H44 | SN74LVC1G08DCKR-GP | 73.01G08.L03 | SC70-5H44 | 13277.22 | 7039.69 | 0 | YES |
| U74 | SC70-5H44 | SN74LVC1G08DCKR-GP | 73.01G08.L03 | SC70-5H44 | 3250 | 7465 | 0 | YES |
| U75 | SC70-5H44 | SN74LVC1G08DCKR-GP | 73.01G08.L03 | SC70-5H44 | 2757.22 | 7464.69 | 0 | YES |
| U76 | SC70-5H44 | SN74LVC1G08DCKR-GP | 73.01G08.L03 | SC70-5H44 | 8955 | 7755 | 0 | YES |
| U77 | SC70-5H44 | SN74LVC1G08DCKR-GP | 73.01G08.L03 | SC70-5H44 | 8492.2199999999993 | 7759.69 | 0 | YES |
| U78 | SC70-5H44 | SN74LVC1G08DCKR-GP | 73.01G08.L03 | SC70-5H44 | 13442.22 | 7039.69 | 0 | YES |
| U79 | SOT-143-6H49 | ADM6315-29D2ARTZ-GP | 74.06315.P7J | SOT-143-6H49 | 10529 | 324 | 0 | NO |
| U80 | SC70-5H44 | SN74LVC1G08DCKR-GP | 73.01G08.L03 | SC70-5H44 | 885 | 5980 | 90 | NO |
| U81 | SC70-5H44 | SN74LVC1G08DCKR-GP | 73.01G08.L03 | SC70-5H44 | 8705 | 406 | 180 | YES |
| U82 | SOT-143-6H49 | ADM6315-26D3ARTZR7-4-GP | 074.06315.0A7J | SOT-143-6H49 | 8891 | 609 | 90 | NO |
| U83 | SC70-5H44 | SN74LVC1G08DCKR-GP | 73.01G08.L03 | SC70-5H44 | 1091.46 | 3595.04 | 90 | NO |
| U134 | MSOP8-1H44 | TMP75AIDGKR-GP | 74.00075.B79 | MSOP8-1H44 | 2130 | 5905 | 90 | NO |
| U136 | MSOP8-1H44 | TMP75AIDGKR-GP | 74.00075.B79 | MSOP8-1H44 | 8955 | 3266 | 0 | NO |
| U187 | SSOIC8-4H36 | TXS0102DCUR-1-GP | 73.00102.007 | SSOIC8-4H36 | 3407.41 | 3269.3 | 270 | NO |
| U194 | SOT-23-5H58 | TPS2065DBVT-GP | 74.02065.07F | SOT-23-5H58 | 1530 | 2240 | 0 | NO |
| U196 | QFN32-G3D3H40 | 9FGV0431AKLFT-GP | 071.90431.0003 | QFN32-G3D3H40 | 6330 | 3566 | 90 | NO |
| U198 | TSOIC24H44 | MAX7311AUG-GP | 071.07311.000W | TSOIC24H44 | 2919.06 | 7463.98 | 0 | NO |
| U199 | TSOIC24H44 | MAX7311AUG-GP | 071.07311.000W | TSOIC24H44 | 5054.0600000000004 | 7983.98 | 0 | NO |
| U200 | TSOIC24H44 | MAX7311AUG-GP | 071.07311.000W | TSOIC24H44 | 8749.06 | 7753.98 | 0 | NO |
| U201 | TSOIC24H44 | MAX7311AUG-GP | 071.07311.000W | TSOIC24H44 | 13196.28 | 7038.67 | 0 | NO |
| U203 | TSOIC24H44 | MAX7311AUG-GP | 071.07311.000W | TSOIC24H44 | 12789 | 3664 | 0 | NO |
| U204 | SC70-5H44 | LMV331IDCKRG4-GP | 74.00331.A2F | SC70-5H44 | 925.88 | 4023.65 | 0 | NO |
| X1 | S-OSC4-7349H75 | OSC-50MHZ-8-GP-U | 82.20043.111 | S-OSC4-7349H75 | 353.66 | 3403.07 | 90 | NO |
| X2 | SMD49-12H34 | XTAL-32D768KHZ-137-GP | 082.30003.0321 | SMD49-12H34 | 5329.09 | 3265.41 | 180 | NO |
| X3 | OSC-3225-4P-4H32 | XTAL-25MHZ-266-GP | 082.30005.0151 | OSC-3225-4P-4H32 | 6005 | 3616 | 90 | NO |
| X11 | SMD49-4H56 | XTAL-25MHZ-96GP | 82.30020.791 | SMD49-4H56 | 284 | 2794 | 270 | NO |
